(lib_symbols
	(symbol "sdi-mipi-bridge:+1V2" (power) (pin_names (offset 0)) (in_bom yes) (on_board yes)
      (property "Reference" "#PWR" (at 0 -3.81 0)
        (effects (font (size 1.27 1.27)) hide)
      )
      (property "Value" "+1V2" (at 0 3.556 0)
        (effects (font (size 1.27 1.27)))
      )
      (property "Footprint" "" (at 0 0 0)
        (effects (font (size 1.27 1.27)) hide)
      )
      (property "Datasheet" "" (at 0 0 0)
        (effects (font (size 1.27 1.27)) hide)
      )
      (symbol "+1V2_0_1"
        (polyline
          (pts
            (xy -0.762 1.27)
            (xy 0 2.54)
          )
          (stroke (width 0) (type default))
          (fill (type none))
        )
        (polyline
          (pts
            (xy 0 0)
            (xy 0 2.54)
          )
          (stroke (width 0) (type default))
          (fill (type none))
        )
        (polyline
          (pts
            (xy 0 2.54)
            (xy 0.762 1.27)
          )
          (stroke (width 0) (type default))
          (fill (type none))
        )
      )
      (symbol "+1V2_1_1"
        (pin power_in line (at 0 0 90) (length 0) hide
          (name "+1V2" (effects (font (size 1.27 1.27))))
          (number "1" (effects (font (size 1.27 1.27))))
        )
      )
    )
	(symbol "sdi-mipi-bridge:+3.3VA" (power) (pin_names (offset 0)) (in_bom yes) (on_board yes)
      (property "Reference" "#PWR" (at 0 -3.81 0)
        (effects (font (size 1.27 1.27)) hide)
      )
      (property "Value" "+3.3VA" (at 0 3.556 0)
        (effects (font (size 1.27 1.27)))
      )
      (property "Footprint" "" (at 0 0 0)
        (effects (font (size 1.27 1.27)) hide)
      )
      (property "Datasheet" "" (at 0 0 0)
        (effects (font (size 1.27 1.27)) hide)
      )
      (symbol "+3.3VA_0_1"
        (polyline
          (pts
            (xy -0.762 1.27)
            (xy 0 2.54)
          )
          (stroke (width 0) (type default))
          (fill (type none))
        )
        (polyline
          (pts
            (xy 0 0)
            (xy 0 2.54)
          )
          (stroke (width 0) (type default))
          (fill (type none))
        )
        (polyline
          (pts
            (xy 0 2.54)
            (xy 0.762 1.27)
          )
          (stroke (width 0) (type default))
          (fill (type none))
        )
      )
      (symbol "+3.3VA_1_1"
        (pin power_in line (at 0 0 90) (length 0) hide
          (name "+3.3VA" (effects (font (size 1.27 1.27))))
          (number "1" (effects (font (size 1.27 1.27))))
        )
      )
    )
	(symbol "sdi-mipi-bridge:+3V3" (power) (pin_numbers hide) (pin_names hide) (in_bom yes) (on_board yes)
      (property "Reference" "#PWR" (at 15.24 -2.54 0)
        (effects (font (size 1.27 1.27) (thickness 0.15)) (justify left bottom) hide)
      )
      (property "Value" "+3V3" (at 15.24 -5.08 0)
        (effects (font (size 1.27 1.27) (thickness 0.15)) (justify left bottom))
      )
      (property "Footprint" "" (at 15.24 -7.62 0)
        (effects (font (size 1.27 1.27) (thickness 0.15)) (justify left bottom) hide)
      )
      (property "Datasheet" "" (at 15.24 -10.16 0)
        (effects (font (size 1.27 1.27) (thickness 0.15)) (justify left bottom) hide)
      )
      (property "Author" "Antmicro" (at 15.24 -7.62 0)
        (effects (font (size 1.27 1.27) (thickness 0.15)) (justify left bottom) hide)
      )
      (property "License" "Apache-2.0" (at 15.24 -10.16 0)
        (effects (font (size 1.27 1.27) (thickness 0.15)) (justify left bottom) hide)
      )
      (symbol "+3V3_1_1"
        (polyline
          (pts
            (xy -0.762 1.27)
            (xy 0 2.54)
          )
          (stroke (width 0.254) (type default))
          (fill (type background))
        )
        (polyline
          (pts
            (xy 0 0)
            (xy 0 2.54)
          )
          (stroke (width 0.254) (type default))
          (fill (type background))
        )
        (polyline
          (pts
            (xy 0 2.54)
            (xy 0.762 1.27)
          )
          (stroke (width 0.254) (type default))
          (fill (type background))
        )
        (pin power_in line (at 0 0 90) (length 0)
          (name "+3V3" (effects (font (size 1.27 1.27))))
          (number "1" (effects (font (size 1.27 1.27))))
        )
      )
    )
	(symbol "sdi-mipi-bridge:C_100n_6V3_0402" (pin_numbers hide) (pin_names hide) (in_bom yes) (on_board yes)
      (property "Reference" "C" (at 20.32 -5.08 0)
        (effects (font (size 1.27 1.27) (thickness 0.15)) (justify left bottom))
      )
      (property "Value" "C_100n_6V3_0402" (at 20.32 -10.16 0)
        (effects (font (size 1.27 1.27) (thickness 0.15)) (justify left bottom) hide)
      )
      (property "Footprint" "sdi-mipi-bridge-footprints:C_0402_1005Metric" (at 20.32 -12.7 0)
        (effects (font (size 1.27 1.27) (thickness 0.15)) (justify left bottom) hide)
      )
      (property "Datasheet" " " (at 20.32 -15.24 0)
        (effects (font (size 1.27 1.27) (thickness 0.15)) (justify left bottom) hide)
      )
      (property "MPN" "0402X104K6R3CT" (at 20.32 -17.78 0)
        (effects (font (size 1.27 1.27) (thickness 0.15)) (justify left bottom) hide)
      )
      (property "Manufacturer" "Walsin" (at 20.32 -20.32 0)
        (effects (font (size 1.27 1.27) (thickness 0.15)) (justify left bottom) hide)
      )
      (property "License" "Apache-2.0" (at 20.32 -22.86 0)
        (effects (font (size 1.27 1.27) (thickness 0.15)) (justify left bottom) hide)
      )
      (property "Author" "Antmicro" (at 20.32 -25.4 0)
        (effects (font (size 1.27 1.27) (thickness 0.15)) (justify left bottom) hide)
      )
      (property "Val" "100n" (at 20.32 -7.62 0)
        (effects (font (size 1.27 1.27) (thickness 0.15)) (justify left bottom))
      )
      (property "Voltage" "" (at 20.32 -27.94 0)
        (effects (font (size 1.27 1.27)) (justify left bottom) hide)
      )
      (property "Dielectric" "" (at 20.32 -30.48 0)
        (effects (font (size 1.27 1.27)) (justify left bottom) hide)
      )
      (property "ki_description" " " (at 0 0 0)
        (effects (font (size 1.27 1.27)) hide)
      )
      (symbol "C_100n_6V3_0402_0_1"
        (polyline
          (pts
            (xy 2.032 -1.524)
            (xy 2.032 1.524)
          )
          (stroke (width 0.3048) (type default))
          (fill (type none))
        )
        (polyline
          (pts
            (xy 3.048 -1.524)
            (xy 3.048 1.524)
          )
          (stroke (width 0.3302) (type default))
          (fill (type none))
        )
      )
      (symbol "C_100n_6V3_0402_1_1"
        (pin passive line (at 0 0 0) (length 2.032)
          (name "~" (effects (font (size 1.27 1.27))))
          (number "1" (effects (font (size 1.27 1.27))))
        )
        (pin passive line (at 5.08 0 180) (length 2.032)
          (name "~" (effects (font (size 1.27 1.27))))
          (number "2" (effects (font (size 1.27 1.27))))
        )
      )
    )
	(symbol "sdi-mipi-bridge:C_100n_6V3_0402_10" (pin_numbers hide) (pin_names hide) (in_bom yes) (on_board yes)
      (property "Reference" "C" (at 20.32 -5.08 0)
        (effects (font (size 1.27 1.27) (thickness 0.15)) (justify left bottom))
      )
      (property "Value" "C_100n_6V3_0402_10" (at 20.32 -10.16 0)
        (effects (font (size 1.27 1.27) (thickness 0.15)) (justify left bottom) hide)
      )
      (property "Footprint" "sdi-mipi-bridge-footprints:C_0402_1005Metric" (at 20.32 -12.7 0)
        (effects (font (size 1.27 1.27) (thickness 0.15)) (justify left bottom) hide)
      )
      (property "Datasheet" " " (at 20.32 -15.24 0)
        (effects (font (size 1.27 1.27) (thickness 0.15)) (justify left bottom) hide)
      )
      (property "MPN" "0402X104K6R3CT" (at 20.32 -17.78 0)
        (effects (font (size 1.27 1.27) (thickness 0.15)) (justify left bottom) hide)
      )
      (property "Manufacturer" "Walsin" (at 20.32 -20.32 0)
        (effects (font (size 1.27 1.27) (thickness 0.15)) (justify left bottom) hide)
      )
      (property "License" "Apache-2.0" (at 20.32 -22.86 0)
        (effects (font (size 1.27 1.27) (thickness 0.15)) (justify left bottom) hide)
      )
      (property "Author" "Antmicro" (at 20.32 -25.4 0)
        (effects (font (size 1.27 1.27) (thickness 0.15)) (justify left bottom) hide)
      )
      (property "Val" "100n" (at 20.32 -7.62 0)
        (effects (font (size 1.27 1.27) (thickness 0.15)) (justify left bottom))
      )
      (property "Voltage" "" (at 20.32 -27.94 0)
        (effects (font (size 1.27 1.27)) (justify left bottom) hide)
      )
      (property "Dielectric" "" (at 20.32 -30.48 0)
        (effects (font (size 1.27 1.27)) (justify left bottom) hide)
      )
      (property "ki_description" " " (at 0 0 0)
        (effects (font (size 1.27 1.27)) hide)
      )
      (symbol "C_100n_6V3_0402_10_0_1"
        (polyline
          (pts
            (xy 2.032 -1.524)
            (xy 2.032 1.524)
          )
          (stroke (width 0.3048) (type default))
          (fill (type none))
        )
        (polyline
          (pts
            (xy 3.048 -1.524)
            (xy 3.048 1.524)
          )
          (stroke (width 0.3302) (type default))
          (fill (type none))
        )
      )
      (symbol "C_100n_6V3_0402_10_1_1"
        (pin passive line (at 0 0 0) (length 2.032)
          (name "~" (effects (font (size 1.27 1.27))))
          (number "1" (effects (font (size 1.27 1.27))))
        )
        (pin passive line (at 5.08 0 180) (length 2.032)
          (name "~" (effects (font (size 1.27 1.27))))
          (number "2" (effects (font (size 1.27 1.27))))
        )
      )
    )
	(symbol "sdi-mipi-bridge:C_100n_6V3_0402_11" (pin_numbers hide) (pin_names hide) (in_bom yes) (on_board yes)
      (property "Reference" "C" (at 20.32 -5.08 0)
        (effects (font (size 1.27 1.27) (thickness 0.15)) (justify left bottom))
      )
      (property "Value" "C_100n_6V3_0402_11" (at 20.32 -10.16 0)
        (effects (font (size 1.27 1.27) (thickness 0.15)) (justify left bottom) hide)
      )
      (property "Footprint" "sdi-mipi-bridge-footprints:C_0402_1005Metric" (at 20.32 -12.7 0)
        (effects (font (size 1.27 1.27) (thickness 0.15)) (justify left bottom) hide)
      )
      (property "Datasheet" " " (at 20.32 -15.24 0)
        (effects (font (size 1.27 1.27) (thickness 0.15)) (justify left bottom) hide)
      )
      (property "MPN" "0402X104K6R3CT" (at 20.32 -17.78 0)
        (effects (font (size 1.27 1.27) (thickness 0.15)) (justify left bottom) hide)
      )
      (property "Manufacturer" "Walsin" (at 20.32 -20.32 0)
        (effects (font (size 1.27 1.27) (thickness 0.15)) (justify left bottom) hide)
      )
      (property "License" "Apache-2.0" (at 20.32 -22.86 0)
        (effects (font (size 1.27 1.27) (thickness 0.15)) (justify left bottom) hide)
      )
      (property "Author" "Antmicro" (at 20.32 -25.4 0)
        (effects (font (size 1.27 1.27) (thickness 0.15)) (justify left bottom) hide)
      )
      (property "Val" "100n" (at 20.32 -7.62 0)
        (effects (font (size 1.27 1.27) (thickness 0.15)) (justify left bottom))
      )
      (property "Voltage" "" (at 20.32 -27.94 0)
        (effects (font (size 1.27 1.27)) (justify left bottom) hide)
      )
      (property "Dielectric" "" (at 20.32 -30.48 0)
        (effects (font (size 1.27 1.27)) (justify left bottom) hide)
      )
      (property "ki_description" " " (at 0 0 0)
        (effects (font (size 1.27 1.27)) hide)
      )
      (symbol "C_100n_6V3_0402_11_0_1"
        (polyline
          (pts
            (xy 2.032 -1.524)
            (xy 2.032 1.524)
          )
          (stroke (width 0.3048) (type default))
          (fill (type none))
        )
        (polyline
          (pts
            (xy 3.048 -1.524)
            (xy 3.048 1.524)
          )
          (stroke (width 0.3302) (type default))
          (fill (type none))
        )
      )
      (symbol "C_100n_6V3_0402_11_1_1"
        (pin passive line (at 0 0 0) (length 2.032)
          (name "~" (effects (font (size 1.27 1.27))))
          (number "1" (effects (font (size 1.27 1.27))))
        )
        (pin passive line (at 5.08 0 180) (length 2.032)
          (name "~" (effects (font (size 1.27 1.27))))
          (number "2" (effects (font (size 1.27 1.27))))
        )
      )
    )
	(symbol "sdi-mipi-bridge:C_10n_0402" (pin_numbers hide) (pin_names hide) (in_bom yes) (on_board yes)
      (property "Reference" "C" (at 20.32 -5.08 0)
        (effects (font (size 1.27 1.27) (thickness 0.15)) (justify left bottom))
      )
      (property "Value" "C_10n_0402" (at 20.32 -10.16 0)
        (effects (font (size 1.27 1.27) (thickness 0.15)) (justify left bottom) hide)
      )
      (property "Footprint" "sdi-mipi-bridge-footprints:C_0402_1005Metric" (at 20.32 -12.7 0)
        (effects (font (size 1.27 1.27) (thickness 0.15)) (justify left bottom) hide)
      )
      (property "Datasheet" "https://search.murata.co.jp/Ceramy/image/img/A01X/G101/ENG/GRM155R71H103KA88-01.pdf" (at 20.32 -15.24 0)
        (effects (font (size 1.27 1.27) (thickness 0.15)) (justify left bottom) hide)
      )
      (property "MPN" "GRM155R71H103KA88D" (at 20.32 -17.78 0)
        (effects (font (size 1.27 1.27) (thickness 0.15)) (justify left bottom) hide)
      )
      (property "Manufacturer" "Murata" (at 20.32 -20.32 0)
        (effects (font (size 1.27 1.27) (thickness 0.15)) (justify left bottom) hide)
      )
      (property "License" "Apache-2.0" (at 20.32 -22.86 0)
        (effects (font (size 1.27 1.27) (thickness 0.15)) (justify left bottom) hide)
      )
      (property "Author" "Antmicro" (at 20.32 -25.4 0)
        (effects (font (size 1.27 1.27) (thickness 0.15)) (justify left bottom) hide)
      )
      (property "Val" "10n" (at 20.32 -7.62 0)
        (effects (font (size 1.27 1.27) (thickness 0.15)) (justify left bottom))
      )
      (property "Voltage" "50V" (at 20.32 -27.94 0)
        (effects (font (size 1.27 1.27)) (justify left bottom) hide)
      )
      (property "Dielectric" "X7R" (at 20.32 -30.48 0)
        (effects (font (size 1.27 1.27)) (justify left bottom) hide)
      )
      (property "ki_description" " " (at 0 0 0)
        (effects (font (size 1.27 1.27)) hide)
      )
      (symbol "C_10n_0402_0_1"
        (polyline
          (pts
            (xy 2.032 -1.524)
            (xy 2.032 1.524)
          )
          (stroke (width 0.3048) (type default))
          (fill (type none))
        )
        (polyline
          (pts
            (xy 3.048 -1.524)
            (xy 3.048 1.524)
          )
          (stroke (width 0.3302) (type default))
          (fill (type none))
        )
      )
      (symbol "C_10n_0402_1_1"
        (pin passive line (at 0 0 0) (length 2.032)
          (name "~" (effects (font (size 1.27 1.27))))
          (number "1" (effects (font (size 1.27 1.27))))
        )
        (pin passive line (at 5.08 0 180) (length 2.032)
          (name "~" (effects (font (size 1.27 1.27))))
          (number "2" (effects (font (size 1.27 1.27))))
        )
      )
    )
	(symbol "sdi-mipi-bridge:C_10n_0402_10" (pin_numbers hide) (pin_names hide) (in_bom yes) (on_board yes)
      (property "Reference" "C" (at 20.32 -5.08 0)
        (effects (font (size 1.27 1.27) (thickness 0.15)) (justify left bottom))
      )
      (property "Value" "C_10n_0402_10" (at 20.32 -10.16 0)
        (effects (font (size 1.27 1.27) (thickness 0.15)) (justify left bottom) hide)
      )
      (property "Footprint" "sdi-mipi-bridge-footprints:C_0402_1005Metric" (at 20.32 -12.7 0)
        (effects (font (size 1.27 1.27) (thickness 0.15)) (justify left bottom) hide)
      )
      (property "Datasheet" "https://search.murata.co.jp/Ceramy/image/img/A01X/G101/ENG/GRM155R71H103KA88-01.pdf" (at 20.32 -15.24 0)
        (effects (font (size 1.27 1.27) (thickness 0.15)) (justify left bottom) hide)
      )
      (property "MPN" "GRM155R71H103KA88D" (at 20.32 -17.78 0)
        (effects (font (size 1.27 1.27) (thickness 0.15)) (justify left bottom) hide)
      )
      (property "Manufacturer" "Murata" (at 20.32 -20.32 0)
        (effects (font (size 1.27 1.27) (thickness 0.15)) (justify left bottom) hide)
      )
      (property "License" "Apache-2.0" (at 20.32 -22.86 0)
        (effects (font (size 1.27 1.27) (thickness 0.15)) (justify left bottom) hide)
      )
      (property "Author" "Antmicro" (at 20.32 -25.4 0)
        (effects (font (size 1.27 1.27) (thickness 0.15)) (justify left bottom) hide)
      )
      (property "Val" "10n" (at 20.32 -7.62 0)
        (effects (font (size 1.27 1.27) (thickness 0.15)) (justify left bottom))
      )
      (property "Voltage" "50V" (at 20.32 -27.94 0)
        (effects (font (size 1.27 1.27)) (justify left bottom) hide)
      )
      (property "Dielectric" "X7R" (at 20.32 -30.48 0)
        (effects (font (size 1.27 1.27)) (justify left bottom) hide)
      )
      (property "ki_description" " " (at 0 0 0)
        (effects (font (size 1.27 1.27)) hide)
      )
      (symbol "C_10n_0402_10_0_1"
        (polyline
          (pts
            (xy 2.032 -1.524)
            (xy 2.032 1.524)
          )
          (stroke (width 0.3048) (type default))
          (fill (type none))
        )
        (polyline
          (pts
            (xy 3.048 -1.524)
            (xy 3.048 1.524)
          )
          (stroke (width 0.3302) (type default))
          (fill (type none))
        )
      )
      (symbol "C_10n_0402_10_1_1"
        (pin passive line (at 0 0 0) (length 2.032)
          (name "~" (effects (font (size 1.27 1.27))))
          (number "1" (effects (font (size 1.27 1.27))))
        )
        (pin passive line (at 5.08 0 180) (length 2.032)
          (name "~" (effects (font (size 1.27 1.27))))
          (number "2" (effects (font (size 1.27 1.27))))
        )
      )
    )
	(symbol "sdi-mipi-bridge:C_10n_0402_11" (pin_numbers hide) (pin_names hide) (in_bom yes) (on_board yes)
      (property "Reference" "C" (at 20.32 -5.08 0)
        (effects (font (size 1.27 1.27) (thickness 0.15)) (justify left bottom))
      )
      (property "Value" "C_10n_0402_11" (at 20.32 -10.16 0)
        (effects (font (size 1.27 1.27) (thickness 0.15)) (justify left bottom) hide)
      )
      (property "Footprint" "sdi-mipi-bridge-footprints:C_0402_1005Metric" (at 20.32 -12.7 0)
        (effects (font (size 1.27 1.27) (thickness 0.15)) (justify left bottom) hide)
      )
      (property "Datasheet" "https://search.murata.co.jp/Ceramy/image/img/A01X/G101/ENG/GRM155R71H103KA88-01.pdf" (at 20.32 -15.24 0)
        (effects (font (size 1.27 1.27) (thickness 0.15)) (justify left bottom) hide)
      )
      (property "MPN" "GRM155R71H103KA88D" (at 20.32 -17.78 0)
        (effects (font (size 1.27 1.27) (thickness 0.15)) (justify left bottom) hide)
      )
      (property "Manufacturer" "Murata" (at 20.32 -20.32 0)
        (effects (font (size 1.27 1.27) (thickness 0.15)) (justify left bottom) hide)
      )
      (property "License" "Apache-2.0" (at 20.32 -22.86 0)
        (effects (font (size 1.27 1.27) (thickness 0.15)) (justify left bottom) hide)
      )
      (property "Author" "Antmicro" (at 20.32 -25.4 0)
        (effects (font (size 1.27 1.27) (thickness 0.15)) (justify left bottom) hide)
      )
      (property "Val" "10n" (at 20.32 -7.62 0)
        (effects (font (size 1.27 1.27) (thickness 0.15)) (justify left bottom))
      )
      (property "Voltage" "50V" (at 20.32 -27.94 0)
        (effects (font (size 1.27 1.27)) (justify left bottom) hide)
      )
      (property "Dielectric" "X7R" (at 20.32 -30.48 0)
        (effects (font (size 1.27 1.27)) (justify left bottom) hide)
      )
      (property "ki_description" " " (at 0 0 0)
        (effects (font (size 1.27 1.27)) hide)
      )
      (symbol "C_10n_0402_11_0_1"
        (polyline
          (pts
            (xy 2.032 -1.524)
            (xy 2.032 1.524)
          )
          (stroke (width 0.3048) (type default))
          (fill (type none))
        )
        (polyline
          (pts
            (xy 3.048 -1.524)
            (xy 3.048 1.524)
          )
          (stroke (width 0.3302) (type default))
          (fill (type none))
        )
      )
      (symbol "C_10n_0402_11_1_1"
        (pin passive line (at 0 0 0) (length 2.032)
          (name "~" (effects (font (size 1.27 1.27))))
          (number "1" (effects (font (size 1.27 1.27))))
        )
        (pin passive line (at 5.08 0 180) (length 2.032)
          (name "~" (effects (font (size 1.27 1.27))))
          (number "2" (effects (font (size 1.27 1.27))))
        )
      )
    )
	(symbol "sdi-mipi-bridge:C_10n_0402_12" (pin_numbers hide) (pin_names hide) (in_bom yes) (on_board yes)
      (property "Reference" "C" (at 20.32 -5.08 0)
        (effects (font (size 1.27 1.27) (thickness 0.15)) (justify left bottom))
      )
      (property "Value" "C_10n_0402_12" (at 20.32 -10.16 0)
        (effects (font (size 1.27 1.27) (thickness 0.15)) (justify left bottom) hide)
      )
      (property "Footprint" "sdi-mipi-bridge-footprints:C_0402_1005Metric" (at 20.32 -12.7 0)
        (effects (font (size 1.27 1.27) (thickness 0.15)) (justify left bottom) hide)
      )
      (property "Datasheet" "https://search.murata.co.jp/Ceramy/image/img/A01X/G101/ENG/GRM155R71H103KA88-01.pdf" (at 20.32 -15.24 0)
        (effects (font (size 1.27 1.27) (thickness 0.15)) (justify left bottom) hide)
      )
      (property "MPN" "GRM155R71H103KA88D" (at 20.32 -17.78 0)
        (effects (font (size 1.27 1.27) (thickness 0.15)) (justify left bottom) hide)
      )
      (property "Manufacturer" "Murata" (at 20.32 -20.32 0)
        (effects (font (size 1.27 1.27) (thickness 0.15)) (justify left bottom) hide)
      )
      (property "License" "Apache-2.0" (at 20.32 -22.86 0)
        (effects (font (size 1.27 1.27) (thickness 0.15)) (justify left bottom) hide)
      )
      (property "Author" "Antmicro" (at 20.32 -25.4 0)
        (effects (font (size 1.27 1.27) (thickness 0.15)) (justify left bottom) hide)
      )
      (property "Val" "10n" (at 20.32 -7.62 0)
        (effects (font (size 1.27 1.27) (thickness 0.15)) (justify left bottom))
      )
      (property "Voltage" "50V" (at 20.32 -27.94 0)
        (effects (font (size 1.27 1.27)) (justify left bottom) hide)
      )
      (property "Dielectric" "X7R" (at 20.32 -30.48 0)
        (effects (font (size 1.27 1.27)) (justify left bottom) hide)
      )
      (property "ki_description" " " (at 0 0 0)
        (effects (font (size 1.27 1.27)) hide)
      )
      (symbol "C_10n_0402_12_0_1"
        (polyline
          (pts
            (xy 2.032 -1.524)
            (xy 2.032 1.524)
          )
          (stroke (width 0.3048) (type default))
          (fill (type none))
        )
        (polyline
          (pts
            (xy 3.048 -1.524)
            (xy 3.048 1.524)
          )
          (stroke (width 0.3302) (type default))
          (fill (type none))
        )
      )
      (symbol "C_10n_0402_12_1_1"
        (pin passive line (at 0 0 0) (length 2.032)
          (name "~" (effects (font (size 1.27 1.27))))
          (number "1" (effects (font (size 1.27 1.27))))
        )
        (pin passive line (at 5.08 0 180) (length 2.032)
          (name "~" (effects (font (size 1.27 1.27))))
          (number "2" (effects (font (size 1.27 1.27))))
        )
      )
    )
	(symbol "sdi-mipi-bridge:C_10n_0402_13" (pin_numbers hide) (pin_names hide) (in_bom yes) (on_board yes)
      (property "Reference" "C" (at 20.32 -5.08 0)
        (effects (font (size 1.27 1.27) (thickness 0.15)) (justify left bottom))
      )
      (property "Value" "C_10n_0402_13" (at 20.32 -10.16 0)
        (effects (font (size 1.27 1.27) (thickness 0.15)) (justify left bottom) hide)
      )
      (property "Footprint" "sdi-mipi-bridge-footprints:C_0402_1005Metric" (at 20.32 -12.7 0)
        (effects (font (size 1.27 1.27) (thickness 0.15)) (justify left bottom) hide)
      )
      (property "Datasheet" "https://search.murata.co.jp/Ceramy/image/img/A01X/G101/ENG/GRM155R71H103KA88-01.pdf" (at 20.32 -15.24 0)
        (effects (font (size 1.27 1.27) (thickness 0.15)) (justify left bottom) hide)
      )
      (property "MPN" "GRM155R71H103KA88D" (at 20.32 -17.78 0)
        (effects (font (size 1.27 1.27) (thickness 0.15)) (justify left bottom) hide)
      )
      (property "Manufacturer" "Murata" (at 20.32 -20.32 0)
        (effects (font (size 1.27 1.27) (thickness 0.15)) (justify left bottom) hide)
      )
      (property "License" "Apache-2.0" (at 20.32 -22.86 0)
        (effects (font (size 1.27 1.27) (thickness 0.15)) (justify left bottom) hide)
      )
      (property "Author" "Antmicro" (at 20.32 -25.4 0)
        (effects (font (size 1.27 1.27) (thickness 0.15)) (justify left bottom) hide)
      )
      (property "Val" "10n" (at 20.32 -7.62 0)
        (effects (font (size 1.27 1.27) (thickness 0.15)) (justify left bottom))
      )
      (property "Voltage" "50V" (at 20.32 -27.94 0)
        (effects (font (size 1.27 1.27)) (justify left bottom) hide)
      )
      (property "Dielectric" "X7R" (at 20.32 -30.48 0)
        (effects (font (size 1.27 1.27)) (justify left bottom) hide)
      )
      (property "ki_description" " " (at 0 0 0)
        (effects (font (size 1.27 1.27)) hide)
      )
      (symbol "C_10n_0402_13_0_1"
        (polyline
          (pts
            (xy 2.032 -1.524)
            (xy 2.032 1.524)
          )
          (stroke (width 0.3048) (type default))
          (fill (type none))
        )
        (polyline
          (pts
            (xy 3.048 -1.524)
            (xy 3.048 1.524)
          )
          (stroke (width 0.3302) (type default))
          (fill (type none))
        )
      )
      (symbol "C_10n_0402_13_1_1"
        (pin passive line (at 0 0 0) (length 2.032)
          (name "~" (effects (font (size 1.27 1.27))))
          (number "1" (effects (font (size 1.27 1.27))))
        )
        (pin passive line (at 5.08 0 180) (length 2.032)
          (name "~" (effects (font (size 1.27 1.27))))
          (number "2" (effects (font (size 1.27 1.27))))
        )
      )
    )
	(symbol "sdi-mipi-bridge:C_10n_0402_14" (pin_numbers hide) (pin_names hide) (in_bom yes) (on_board yes)
      (property "Reference" "C" (at 20.32 -5.08 0)
        (effects (font (size 1.27 1.27) (thickness 0.15)) (justify left bottom))
      )
      (property "Value" "C_10n_0402_14" (at 20.32 -10.16 0)
        (effects (font (size 1.27 1.27) (thickness 0.15)) (justify left bottom) hide)
      )
      (property "Footprint" "sdi-mipi-bridge-footprints:C_0402_1005Metric" (at 20.32 -12.7 0)
        (effects (font (size 1.27 1.27) (thickness 0.15)) (justify left bottom) hide)
      )
      (property "Datasheet" "https://search.murata.co.jp/Ceramy/image/img/A01X/G101/ENG/GRM155R71H103KA88-01.pdf" (at 20.32 -15.24 0)
        (effects (font (size 1.27 1.27) (thickness 0.15)) (justify left bottom) hide)
      )
      (property "MPN" "GRM155R71H103KA88D" (at 20.32 -17.78 0)
        (effects (font (size 1.27 1.27) (thickness 0.15)) (justify left bottom) hide)
      )
      (property "Manufacturer" "Murata" (at 20.32 -20.32 0)
        (effects (font (size 1.27 1.27) (thickness 0.15)) (justify left bottom) hide)
      )
      (property "License" "Apache-2.0" (at 20.32 -22.86 0)
        (effects (font (size 1.27 1.27) (thickness 0.15)) (justify left bottom) hide)
      )
      (property "Author" "Antmicro" (at 20.32 -25.4 0)
        (effects (font (size 1.27 1.27) (thickness 0.15)) (justify left bottom) hide)
      )
      (property "Val" "10n" (at 20.32 -7.62 0)
        (effects (font (size 1.27 1.27) (thickness 0.15)) (justify left bottom))
      )
      (property "Voltage" "50V" (at 20.32 -27.94 0)
        (effects (font (size 1.27 1.27)) (justify left bottom) hide)
      )
      (property "Dielectric" "X7R" (at 20.32 -30.48 0)
        (effects (font (size 1.27 1.27)) (justify left bottom) hide)
      )
      (property "ki_description" " " (at 0 0 0)
        (effects (font (size 1.27 1.27)) hide)
      )
      (symbol "C_10n_0402_14_0_1"
        (polyline
          (pts
            (xy 2.032 -1.524)
            (xy 2.032 1.524)
          )
          (stroke (width 0.3048) (type default))
          (fill (type none))
        )
        (polyline
          (pts
            (xy 3.048 -1.524)
            (xy 3.048 1.524)
          )
          (stroke (width 0.3302) (type default))
          (fill (type none))
        )
      )
      (symbol "C_10n_0402_14_1_1"
        (pin passive line (at 0 0 0) (length 2.032)
          (name "~" (effects (font (size 1.27 1.27))))
          (number "1" (effects (font (size 1.27 1.27))))
        )
        (pin passive line (at 5.08 0 180) (length 2.032)
          (name "~" (effects (font (size 1.27 1.27))))
          (number "2" (effects (font (size 1.27 1.27))))
        )
      )
    )
	(symbol "sdi-mipi-bridge:C_10n_0402_15" (pin_numbers hide) (pin_names hide) (in_bom yes) (on_board yes)
      (property "Reference" "C" (at 20.32 -5.08 0)
        (effects (font (size 1.27 1.27) (thickness 0.15)) (justify left bottom))
      )
      (property "Value" "C_10n_0402_15" (at 20.32 -10.16 0)
        (effects (font (size 1.27 1.27) (thickness 0.15)) (justify left bottom) hide)
      )
      (property "Footprint" "sdi-mipi-bridge-footprints:C_0402_1005Metric" (at 20.32 -12.7 0)
        (effects (font (size 1.27 1.27) (thickness 0.15)) (justify left bottom) hide)
      )
      (property "Datasheet" "https://search.murata.co.jp/Ceramy/image/img/A01X/G101/ENG/GRM155R71H103KA88-01.pdf" (at 20.32 -15.24 0)
        (effects (font (size 1.27 1.27) (thickness 0.15)) (justify left bottom) hide)
      )
      (property "MPN" "GRM155R71H103KA88D" (at 20.32 -17.78 0)
        (effects (font (size 1.27 1.27) (thickness 0.15)) (justify left bottom) hide)
      )
      (property "Manufacturer" "Murata" (at 20.32 -20.32 0)
        (effects (font (size 1.27 1.27) (thickness 0.15)) (justify left bottom) hide)
      )
      (property "License" "Apache-2.0" (at 20.32 -22.86 0)
        (effects (font (size 1.27 1.27) (thickness 0.15)) (justify left bottom) hide)
      )
      (property "Author" "Antmicro" (at 20.32 -25.4 0)
        (effects (font (size 1.27 1.27) (thickness 0.15)) (justify left bottom) hide)
      )
      (property "Val" "10n" (at 20.32 -7.62 0)
        (effects (font (size 1.27 1.27) (thickness 0.15)) (justify left bottom))
      )
      (property "Voltage" "50V" (at 20.32 -27.94 0)
        (effects (font (size 1.27 1.27)) (justify left bottom) hide)
      )
      (property "Dielectric" "X7R" (at 20.32 -30.48 0)
        (effects (font (size 1.27 1.27)) (justify left bottom) hide)
      )
      (property "ki_description" " " (at 0 0 0)
        (effects (font (size 1.27 1.27)) hide)
      )
      (symbol "C_10n_0402_15_0_1"
        (polyline
          (pts
            (xy 2.032 -1.524)
            (xy 2.032 1.524)
          )
          (stroke (width 0.3048) (type default))
          (fill (type none))
        )
        (polyline
          (pts
            (xy 3.048 -1.524)
            (xy 3.048 1.524)
          )
          (stroke (width 0.3302) (type default))
          (fill (type none))
        )
      )
      (symbol "C_10n_0402_15_1_1"
        (pin passive line (at 0 0 0) (length 2.032)
          (name "~" (effects (font (size 1.27 1.27))))
          (number "1" (effects (font (size 1.27 1.27))))
        )
        (pin passive line (at 5.08 0 180) (length 2.032)
          (name "~" (effects (font (size 1.27 1.27))))
          (number "2" (effects (font (size 1.27 1.27))))
        )
      )
    )
	(symbol "sdi-mipi-bridge:C_10n_0402_16" (pin_numbers hide) (pin_names hide) (in_bom yes) (on_board yes)
      (property "Reference" "C" (at 20.32 -5.08 0)
        (effects (font (size 1.27 1.27) (thickness 0.15)) (justify left bottom))
      )
      (property "Value" "C_10n_0402_16" (at 20.32 -10.16 0)
        (effects (font (size 1.27 1.27) (thickness 0.15)) (justify left bottom) hide)
      )
      (property "Footprint" "sdi-mipi-bridge-footprints:C_0402_1005Metric" (at 20.32 -12.7 0)
        (effects (font (size 1.27 1.27) (thickness 0.15)) (justify left bottom) hide)
      )
      (property "Datasheet" "https://search.murata.co.jp/Ceramy/image/img/A01X/G101/ENG/GRM155R71H103KA88-01.pdf" (at 20.32 -15.24 0)
        (effects (font (size 1.27 1.27) (thickness 0.15)) (justify left bottom) hide)
      )
      (property "MPN" "GRM155R71H103KA88D" (at 20.32 -17.78 0)
        (effects (font (size 1.27 1.27) (thickness 0.15)) (justify left bottom) hide)
      )
      (property "Manufacturer" "Murata" (at 20.32 -20.32 0)
        (effects (font (size 1.27 1.27) (thickness 0.15)) (justify left bottom) hide)
      )
      (property "License" "Apache-2.0" (at 20.32 -22.86 0)
        (effects (font (size 1.27 1.27) (thickness 0.15)) (justify left bottom) hide)
      )
      (property "Author" "Antmicro" (at 20.32 -25.4 0)
        (effects (font (size 1.27 1.27) (thickness 0.15)) (justify left bottom) hide)
      )
      (property "Val" "10n" (at 20.32 -7.62 0)
        (effects (font (size 1.27 1.27) (thickness 0.15)) (justify left bottom))
      )
      (property "Voltage" "50V" (at 20.32 -27.94 0)
        (effects (font (size 1.27 1.27)) (justify left bottom) hide)
      )
      (property "Dielectric" "X7R" (at 20.32 -30.48 0)
        (effects (font (size 1.27 1.27)) (justify left bottom) hide)
      )
      (property "ki_description" " " (at 0 0 0)
        (effects (font (size 1.27 1.27)) hide)
      )
      (symbol "C_10n_0402_16_0_1"
        (polyline
          (pts
            (xy 2.032 -1.524)
            (xy 2.032 1.524)
          )
          (stroke (width 0.3048) (type default))
          (fill (type none))
        )
        (polyline
          (pts
            (xy 3.048 -1.524)
            (xy 3.048 1.524)
          )
          (stroke (width 0.3302) (type default))
          (fill (type none))
        )
      )
      (symbol "C_10n_0402_16_1_1"
        (pin passive line (at 0 0 0) (length 2.032)
          (name "~" (effects (font (size 1.27 1.27))))
          (number "1" (effects (font (size 1.27 1.27))))
        )
        (pin passive line (at 5.08 0 180) (length 2.032)
          (name "~" (effects (font (size 1.27 1.27))))
          (number "2" (effects (font (size 1.27 1.27))))
        )
      )
    )
	(symbol "sdi-mipi-bridge:C_10n_0402_17" (pin_numbers hide) (pin_names hide) (in_bom yes) (on_board yes)
      (property "Reference" "C" (at 20.32 -5.08 0)
        (effects (font (size 1.27 1.27) (thickness 0.15)) (justify left bottom))
      )
      (property "Value" "C_10n_0402_17" (at 20.32 -10.16 0)
        (effects (font (size 1.27 1.27) (thickness 0.15)) (justify left bottom) hide)
      )
      (property "Footprint" "sdi-mipi-bridge-footprints:C_0402_1005Metric" (at 20.32 -12.7 0)
        (effects (font (size 1.27 1.27) (thickness 0.15)) (justify left bottom) hide)
      )
      (property "Datasheet" "https://search.murata.co.jp/Ceramy/image/img/A01X/G101/ENG/GRM155R71H103KA88-01.pdf" (at 20.32 -15.24 0)
        (effects (font (size 1.27 1.27) (thickness 0.15)) (justify left bottom) hide)
      )
      (property "MPN" "GRM155R71H103KA88D" (at 20.32 -17.78 0)
        (effects (font (size 1.27 1.27) (thickness 0.15)) (justify left bottom) hide)
      )
      (property "Manufacturer" "Murata" (at 20.32 -20.32 0)
        (effects (font (size 1.27 1.27) (thickness 0.15)) (justify left bottom) hide)
      )
      (property "License" "Apache-2.0" (at 20.32 -22.86 0)
        (effects (font (size 1.27 1.27) (thickness 0.15)) (justify left bottom) hide)
      )
      (property "Author" "Antmicro" (at 20.32 -25.4 0)
        (effects (font (size 1.27 1.27) (thickness 0.15)) (justify left bottom) hide)
      )
      (property "Val" "10n" (at 20.32 -7.62 0)
        (effects (font (size 1.27 1.27) (thickness 0.15)) (justify left bottom))
      )
      (property "Voltage" "50V" (at 20.32 -27.94 0)
        (effects (font (size 1.27 1.27)) (justify left bottom) hide)
      )
      (property "Dielectric" "X7R" (at 20.32 -30.48 0)
        (effects (font (size 1.27 1.27)) (justify left bottom) hide)
      )
      (property "ki_description" " " (at 0 0 0)
        (effects (font (size 1.27 1.27)) hide)
      )
      (symbol "C_10n_0402_17_0_1"
        (polyline
          (pts
            (xy 2.032 -1.524)
            (xy 2.032 1.524)
          )
          (stroke (width 0.3048) (type default))
          (fill (type none))
        )
        (polyline
          (pts
            (xy 3.048 -1.524)
            (xy 3.048 1.524)
          )
          (stroke (width 0.3302) (type default))
          (fill (type none))
        )
      )
      (symbol "C_10n_0402_17_1_1"
        (pin passive line (at 0 0 0) (length 2.032)
          (name "~" (effects (font (size 1.27 1.27))))
          (number "1" (effects (font (size 1.27 1.27))))
        )
        (pin passive line (at 5.08 0 180) (length 2.032)
          (name "~" (effects (font (size 1.27 1.27))))
          (number "2" (effects (font (size 1.27 1.27))))
        )
      )
    )
	(symbol "sdi-mipi-bridge:C_10n_0402_18" (pin_numbers hide) (pin_names hide) (in_bom yes) (on_board yes)
      (property "Reference" "C" (at 20.32 -5.08 0)
        (effects (font (size 1.27 1.27) (thickness 0.15)) (justify left bottom))
      )
      (property "Value" "C_10n_0402_18" (at 20.32 -10.16 0)
        (effects (font (size 1.27 1.27) (thickness 0.15)) (justify left bottom) hide)
      )
      (property "Footprint" "sdi-mipi-bridge-footprints:C_0402_1005Metric" (at 20.32 -12.7 0)
        (effects (font (size 1.27 1.27) (thickness 0.15)) (justify left bottom) hide)
      )
      (property "Datasheet" "https://search.murata.co.jp/Ceramy/image/img/A01X/G101/ENG/GRM155R71H103KA88-01.pdf" (at 20.32 -15.24 0)
        (effects (font (size 1.27 1.27) (thickness 0.15)) (justify left bottom) hide)
      )
      (property "MPN" "GRM155R71H103KA88D" (at 20.32 -17.78 0)
        (effects (font (size 1.27 1.27) (thickness 0.15)) (justify left bottom) hide)
      )
      (property "Manufacturer" "Murata" (at 20.32 -20.32 0)
        (effects (font (size 1.27 1.27) (thickness 0.15)) (justify left bottom) hide)
      )
      (property "License" "Apache-2.0" (at 20.32 -22.86 0)
        (effects (font (size 1.27 1.27) (thickness 0.15)) (justify left bottom) hide)
      )
      (property "Author" "Antmicro" (at 20.32 -25.4 0)
        (effects (font (size 1.27 1.27) (thickness 0.15)) (justify left bottom) hide)
      )
      (property "Val" "10n" (at 20.32 -7.62 0)
        (effects (font (size 1.27 1.27) (thickness 0.15)) (justify left bottom))
      )
      (property "Voltage" "50V" (at 20.32 -27.94 0)
        (effects (font (size 1.27 1.27)) (justify left bottom) hide)
      )
      (property "Dielectric" "X7R" (at 20.32 -30.48 0)
        (effects (font (size 1.27 1.27)) (justify left bottom) hide)
      )
      (property "ki_description" " " (at 0 0 0)
        (effects (font (size 1.27 1.27)) hide)
      )
      (symbol "C_10n_0402_18_0_1"
        (polyline
          (pts
            (xy 2.032 -1.524)
            (xy 2.032 1.524)
          )
          (stroke (width 0.3048) (type default))
          (fill (type none))
        )
        (polyline
          (pts
            (xy 3.048 -1.524)
            (xy 3.048 1.524)
          )
          (stroke (width 0.3302) (type default))
          (fill (type none))
        )
      )
      (symbol "C_10n_0402_18_1_1"
        (pin passive line (at 0 0 0) (length 2.032)
          (name "~" (effects (font (size 1.27 1.27))))
          (number "1" (effects (font (size 1.27 1.27))))
        )
        (pin passive line (at 5.08 0 180) (length 2.032)
          (name "~" (effects (font (size 1.27 1.27))))
          (number "2" (effects (font (size 1.27 1.27))))
        )
      )
    )
	(symbol "sdi-mipi-bridge:C_10n_0402_19" (pin_numbers hide) (pin_names hide) (in_bom yes) (on_board yes)
      (property "Reference" "C" (at 20.32 -5.08 0)
        (effects (font (size 1.27 1.27) (thickness 0.15)) (justify left bottom))
      )
      (property "Value" "C_10n_0402_19" (at 20.32 -10.16 0)
        (effects (font (size 1.27 1.27) (thickness 0.15)) (justify left bottom) hide)
      )
      (property "Footprint" "sdi-mipi-bridge-footprints:C_0402_1005Metric" (at 20.32 -12.7 0)
        (effects (font (size 1.27 1.27) (thickness 0.15)) (justify left bottom) hide)
      )
      (property "Datasheet" "https://search.murata.co.jp/Ceramy/image/img/A01X/G101/ENG/GRM155R71H103KA88-01.pdf" (at 20.32 -15.24 0)
        (effects (font (size 1.27 1.27) (thickness 0.15)) (justify left bottom) hide)
      )
      (property "MPN" "GRM155R71H103KA88D" (at 20.32 -17.78 0)
        (effects (font (size 1.27 1.27) (thickness 0.15)) (justify left bottom) hide)
      )
      (property "Manufacturer" "Murata" (at 20.32 -20.32 0)
        (effects (font (size 1.27 1.27) (thickness 0.15)) (justify left bottom) hide)
      )
      (property "License" "Apache-2.0" (at 20.32 -22.86 0)
        (effects (font (size 1.27 1.27) (thickness 0.15)) (justify left bottom) hide)
      )
      (property "Author" "Antmicro" (at 20.32 -25.4 0)
        (effects (font (size 1.27 1.27) (thickness 0.15)) (justify left bottom) hide)
      )
      (property "Val" "10n" (at 20.32 -7.62 0)
        (effects (font (size 1.27 1.27) (thickness 0.15)) (justify left bottom))
      )
      (property "Voltage" "50V" (at 20.32 -27.94 0)
        (effects (font (size 1.27 1.27)) (justify left bottom) hide)
      )
      (property "Dielectric" "X7R" (at 20.32 -30.48 0)
        (effects (font (size 1.27 1.27)) (justify left bottom) hide)
      )
      (property "ki_description" " " (at 0 0 0)
        (effects (font (size 1.27 1.27)) hide)
      )
      (symbol "C_10n_0402_19_0_1"
        (polyline
          (pts
            (xy 2.032 -1.524)
            (xy 2.032 1.524)
          )
          (stroke (width 0.3048) (type default))
          (fill (type none))
        )
        (polyline
          (pts
            (xy 3.048 -1.524)
            (xy 3.048 1.524)
          )
          (stroke (width 0.3302) (type default))
          (fill (type none))
        )
      )
      (symbol "C_10n_0402_19_1_1"
        (pin passive line (at 0 0 0) (length 2.032)
          (name "~" (effects (font (size 1.27 1.27))))
          (number "1" (effects (font (size 1.27 1.27))))
        )
        (pin passive line (at 5.08 0 180) (length 2.032)
          (name "~" (effects (font (size 1.27 1.27))))
          (number "2" (effects (font (size 1.27 1.27))))
        )
      )
    )
	(symbol "sdi-mipi-bridge:C_10n_0402_20" (pin_numbers hide) (pin_names hide) (in_bom yes) (on_board yes)
      (property "Reference" "C" (at 20.32 -5.08 0)
        (effects (font (size 1.27 1.27) (thickness 0.15)) (justify left bottom))
      )
      (property "Value" "C_10n_0402_20" (at 20.32 -10.16 0)
        (effects (font (size 1.27 1.27) (thickness 0.15)) (justify left bottom) hide)
      )
      (property "Footprint" "sdi-mipi-bridge-footprints:C_0402_1005Metric" (at 20.32 -12.7 0)
        (effects (font (size 1.27 1.27) (thickness 0.15)) (justify left bottom) hide)
      )
      (property "Datasheet" "https://search.murata.co.jp/Ceramy/image/img/A01X/G101/ENG/GRM155R71H103KA88-01.pdf" (at 20.32 -15.24 0)
        (effects (font (size 1.27 1.27) (thickness 0.15)) (justify left bottom) hide)
      )
      (property "MPN" "GRM155R71H103KA88D" (at 20.32 -17.78 0)
        (effects (font (size 1.27 1.27) (thickness 0.15)) (justify left bottom) hide)
      )
      (property "Manufacturer" "Murata" (at 20.32 -20.32 0)
        (effects (font (size 1.27 1.27) (thickness 0.15)) (justify left bottom) hide)
      )
      (property "License" "Apache-2.0" (at 20.32 -22.86 0)
        (effects (font (size 1.27 1.27) (thickness 0.15)) (justify left bottom) hide)
      )
      (property "Author" "Antmicro" (at 20.32 -25.4 0)
        (effects (font (size 1.27 1.27) (thickness 0.15)) (justify left bottom) hide)
      )
      (property "Val" "10n" (at 20.32 -7.62 0)
        (effects (font (size 1.27 1.27) (thickness 0.15)) (justify left bottom))
      )
      (property "Voltage" "50V" (at 20.32 -27.94 0)
        (effects (font (size 1.27 1.27)) (justify left bottom) hide)
      )
      (property "Dielectric" "X7R" (at 20.32 -30.48 0)
        (effects (font (size 1.27 1.27)) (justify left bottom) hide)
      )
      (property "ki_description" " " (at 0 0 0)
        (effects (font (size 1.27 1.27)) hide)
      )
      (symbol "C_10n_0402_20_0_1"
        (polyline
          (pts
            (xy 2.032 -1.524)
            (xy 2.032 1.524)
          )
          (stroke (width 0.3048) (type default))
          (fill (type none))
        )
        (polyline
          (pts
            (xy 3.048 -1.524)
            (xy 3.048 1.524)
          )
          (stroke (width 0.3302) (type default))
          (fill (type none))
        )
      )
      (symbol "C_10n_0402_20_1_1"
        (pin passive line (at 0 0 0) (length 2.032)
          (name "~" (effects (font (size 1.27 1.27))))
          (number "1" (effects (font (size 1.27 1.27))))
        )
        (pin passive line (at 5.08 0 180) (length 2.032)
          (name "~" (effects (font (size 1.27 1.27))))
          (number "2" (effects (font (size 1.27 1.27))))
        )
      )
    )
	(symbol "sdi-mipi-bridge:C_10n_0402_21" (pin_numbers hide) (pin_names hide) (in_bom yes) (on_board yes)
      (property "Reference" "C" (at 20.32 -5.08 0)
        (effects (font (size 1.27 1.27) (thickness 0.15)) (justify left bottom))
      )
      (property "Value" "C_10n_0402_21" (at 20.32 -10.16 0)
        (effects (font (size 1.27 1.27) (thickness 0.15)) (justify left bottom) hide)
      )
      (property "Footprint" "sdi-mipi-bridge-footprints:C_0402_1005Metric" (at 20.32 -12.7 0)
        (effects (font (size 1.27 1.27) (thickness 0.15)) (justify left bottom) hide)
      )
      (property "Datasheet" "https://search.murata.co.jp/Ceramy/image/img/A01X/G101/ENG/GRM155R71H103KA88-01.pdf" (at 20.32 -15.24 0)
        (effects (font (size 1.27 1.27) (thickness 0.15)) (justify left bottom) hide)
      )
      (property "MPN" "GRM155R71H103KA88D" (at 20.32 -17.78 0)
        (effects (font (size 1.27 1.27) (thickness 0.15)) (justify left bottom) hide)
      )
      (property "Manufacturer" "Murata" (at 20.32 -20.32 0)
        (effects (font (size 1.27 1.27) (thickness 0.15)) (justify left bottom) hide)
      )
      (property "License" "Apache-2.0" (at 20.32 -22.86 0)
        (effects (font (size 1.27 1.27) (thickness 0.15)) (justify left bottom) hide)
      )
      (property "Author" "Antmicro" (at 20.32 -25.4 0)
        (effects (font (size 1.27 1.27) (thickness 0.15)) (justify left bottom) hide)
      )
      (property "Val" "10n" (at 20.32 -7.62 0)
        (effects (font (size 1.27 1.27) (thickness 0.15)) (justify left bottom))
      )
      (property "Voltage" "50V" (at 20.32 -27.94 0)
        (effects (font (size 1.27 1.27)) (justify left bottom) hide)
      )
      (property "Dielectric" "X7R" (at 20.32 -30.48 0)
        (effects (font (size 1.27 1.27)) (justify left bottom) hide)
      )
      (property "ki_description" " " (at 0 0 0)
        (effects (font (size 1.27 1.27)) hide)
      )
      (symbol "C_10n_0402_21_0_1"
        (polyline
          (pts
            (xy 2.032 -1.524)
            (xy 2.032 1.524)
          )
          (stroke (width 0.3048) (type default))
          (fill (type none))
        )
        (polyline
          (pts
            (xy 3.048 -1.524)
            (xy 3.048 1.524)
          )
          (stroke (width 0.3302) (type default))
          (fill (type none))
        )
      )
      (symbol "C_10n_0402_21_1_1"
        (pin passive line (at 0 0 0) (length 2.032)
          (name "~" (effects (font (size 1.27 1.27))))
          (number "1" (effects (font (size 1.27 1.27))))
        )
        (pin passive line (at 5.08 0 180) (length 2.032)
          (name "~" (effects (font (size 1.27 1.27))))
          (number "2" (effects (font (size 1.27 1.27))))
        )
      )
    )
	(symbol "sdi-mipi-bridge:C_10n_0402_22" (pin_numbers hide) (pin_names hide) (in_bom yes) (on_board yes)
      (property "Reference" "C" (at 20.32 -5.08 0)
        (effects (font (size 1.27 1.27) (thickness 0.15)) (justify left bottom))
      )
      (property "Value" "C_10n_0402_22" (at 20.32 -10.16 0)
        (effects (font (size 1.27 1.27) (thickness 0.15)) (justify left bottom) hide)
      )
      (property "Footprint" "sdi-mipi-bridge-footprints:C_0402_1005Metric" (at 20.32 -12.7 0)
        (effects (font (size 1.27 1.27) (thickness 0.15)) (justify left bottom) hide)
      )
      (property "Datasheet" "https://search.murata.co.jp/Ceramy/image/img/A01X/G101/ENG/GRM155R71H103KA88-01.pdf" (at 20.32 -15.24 0)
        (effects (font (size 1.27 1.27) (thickness 0.15)) (justify left bottom) hide)
      )
      (property "MPN" "GRM155R71H103KA88D" (at 20.32 -17.78 0)
        (effects (font (size 1.27 1.27) (thickness 0.15)) (justify left bottom) hide)
      )
      (property "Manufacturer" "Murata" (at 20.32 -20.32 0)
        (effects (font (size 1.27 1.27) (thickness 0.15)) (justify left bottom) hide)
      )
      (property "License" "Apache-2.0" (at 20.32 -22.86 0)
        (effects (font (size 1.27 1.27) (thickness 0.15)) (justify left bottom) hide)
      )
      (property "Author" "Antmicro" (at 20.32 -25.4 0)
        (effects (font (size 1.27 1.27) (thickness 0.15)) (justify left bottom) hide)
      )
      (property "Val" "10n" (at 20.32 -7.62 0)
        (effects (font (size 1.27 1.27) (thickness 0.15)) (justify left bottom))
      )
      (property "Voltage" "50V" (at 20.32 -27.94 0)
        (effects (font (size 1.27 1.27)) (justify left bottom) hide)
      )
      (property "Dielectric" "X7R" (at 20.32 -30.48 0)
        (effects (font (size 1.27 1.27)) (justify left bottom) hide)
      )
      (property "ki_description" " " (at 0 0 0)
        (effects (font (size 1.27 1.27)) hide)
      )
      (symbol "C_10n_0402_22_0_1"
        (polyline
          (pts
            (xy 2.032 -1.524)
            (xy 2.032 1.524)
          )
          (stroke (width 0.3048) (type default))
          (fill (type none))
        )
        (polyline
          (pts
            (xy 3.048 -1.524)
            (xy 3.048 1.524)
          )
          (stroke (width 0.3302) (type default))
          (fill (type none))
        )
      )
      (symbol "C_10n_0402_22_1_1"
        (pin passive line (at 0 0 0) (length 2.032)
          (name "~" (effects (font (size 1.27 1.27))))
          (number "1" (effects (font (size 1.27 1.27))))
        )
        (pin passive line (at 5.08 0 180) (length 2.032)
          (name "~" (effects (font (size 1.27 1.27))))
          (number "2" (effects (font (size 1.27 1.27))))
        )
      )
    )
	(symbol "sdi-mipi-bridge:C_10n_0402_23" (pin_numbers hide) (pin_names hide) (in_bom yes) (on_board yes)
      (property "Reference" "C" (at 20.32 -5.08 0)
        (effects (font (size 1.27 1.27) (thickness 0.15)) (justify left bottom))
      )
      (property "Value" "C_10n_0402_23" (at 20.32 -10.16 0)
        (effects (font (size 1.27 1.27) (thickness 0.15)) (justify left bottom) hide)
      )
      (property "Footprint" "sdi-mipi-bridge-footprints:C_0402_1005Metric" (at 20.32 -12.7 0)
        (effects (font (size 1.27 1.27) (thickness 0.15)) (justify left bottom) hide)
      )
      (property "Datasheet" "https://search.murata.co.jp/Ceramy/image/img/A01X/G101/ENG/GRM155R71H103KA88-01.pdf" (at 20.32 -15.24 0)
        (effects (font (size 1.27 1.27) (thickness 0.15)) (justify left bottom) hide)
      )
      (property "MPN" "GRM155R71H103KA88D" (at 20.32 -17.78 0)
        (effects (font (size 1.27 1.27) (thickness 0.15)) (justify left bottom) hide)
      )
      (property "Manufacturer" "Murata" (at 20.32 -20.32 0)
        (effects (font (size 1.27 1.27) (thickness 0.15)) (justify left bottom) hide)
      )
      (property "License" "Apache-2.0" (at 20.32 -22.86 0)
        (effects (font (size 1.27 1.27) (thickness 0.15)) (justify left bottom) hide)
      )
      (property "Author" "Antmicro" (at 20.32 -25.4 0)
        (effects (font (size 1.27 1.27) (thickness 0.15)) (justify left bottom) hide)
      )
      (property "Val" "10n" (at 20.32 -7.62 0)
        (effects (font (size 1.27 1.27) (thickness 0.15)) (justify left bottom))
      )
      (property "Voltage" "50V" (at 20.32 -27.94 0)
        (effects (font (size 1.27 1.27)) (justify left bottom) hide)
      )
      (property "Dielectric" "X7R" (at 20.32 -30.48 0)
        (effects (font (size 1.27 1.27)) (justify left bottom) hide)
      )
      (property "ki_description" " " (at 0 0 0)
        (effects (font (size 1.27 1.27)) hide)
      )
      (symbol "C_10n_0402_23_0_1"
        (polyline
          (pts
            (xy 2.032 -1.524)
            (xy 2.032 1.524)
          )
          (stroke (width 0.3048) (type default))
          (fill (type none))
        )
        (polyline
          (pts
            (xy 3.048 -1.524)
            (xy 3.048 1.524)
          )
          (stroke (width 0.3302) (type default))
          (fill (type none))
        )
      )
      (symbol "C_10n_0402_23_1_1"
        (pin passive line (at 0 0 0) (length 2.032)
          (name "~" (effects (font (size 1.27 1.27))))
          (number "1" (effects (font (size 1.27 1.27))))
        )
        (pin passive line (at 5.08 0 180) (length 2.032)
          (name "~" (effects (font (size 1.27 1.27))))
          (number "2" (effects (font (size 1.27 1.27))))
        )
      )
    )
	(symbol "sdi-mipi-bridge:C_10n_0402_24" (pin_numbers hide) (pin_names hide) (in_bom yes) (on_board yes)
      (property "Reference" "C" (at 20.32 -5.08 0)
        (effects (font (size 1.27 1.27) (thickness 0.15)) (justify left bottom))
      )
      (property "Value" "C_10n_0402_24" (at 20.32 -10.16 0)
        (effects (font (size 1.27 1.27) (thickness 0.15)) (justify left bottom) hide)
      )
      (property "Footprint" "sdi-mipi-bridge-footprints:C_0402_1005Metric" (at 20.32 -12.7 0)
        (effects (font (size 1.27 1.27) (thickness 0.15)) (justify left bottom) hide)
      )
      (property "Datasheet" "https://search.murata.co.jp/Ceramy/image/img/A01X/G101/ENG/GRM155R71H103KA88-01.pdf" (at 20.32 -15.24 0)
        (effects (font (size 1.27 1.27) (thickness 0.15)) (justify left bottom) hide)
      )
      (property "MPN" "GRM155R71H103KA88D" (at 20.32 -17.78 0)
        (effects (font (size 1.27 1.27) (thickness 0.15)) (justify left bottom) hide)
      )
      (property "Manufacturer" "Murata" (at 20.32 -20.32 0)
        (effects (font (size 1.27 1.27) (thickness 0.15)) (justify left bottom) hide)
      )
      (property "License" "Apache-2.0" (at 20.32 -22.86 0)
        (effects (font (size 1.27 1.27) (thickness 0.15)) (justify left bottom) hide)
      )
      (property "Author" "Antmicro" (at 20.32 -25.4 0)
        (effects (font (size 1.27 1.27) (thickness 0.15)) (justify left bottom) hide)
      )
      (property "Val" "10n" (at 20.32 -7.62 0)
        (effects (font (size 1.27 1.27) (thickness 0.15)) (justify left bottom))
      )
      (property "Voltage" "50V" (at 20.32 -27.94 0)
        (effects (font (size 1.27 1.27)) (justify left bottom) hide)
      )
      (property "Dielectric" "X7R" (at 20.32 -30.48 0)
        (effects (font (size 1.27 1.27)) (justify left bottom) hide)
      )
      (property "ki_description" " " (at 0 0 0)
        (effects (font (size 1.27 1.27)) hide)
      )
      (symbol "C_10n_0402_24_0_1"
        (polyline
          (pts
            (xy 2.032 -1.524)
            (xy 2.032 1.524)
          )
          (stroke (width 0.3048) (type default))
          (fill (type none))
        )
        (polyline
          (pts
            (xy 3.048 -1.524)
            (xy 3.048 1.524)
          )
          (stroke (width 0.3302) (type default))
          (fill (type none))
        )
      )
      (symbol "C_10n_0402_24_1_1"
        (pin passive line (at 0 0 0) (length 2.032)
          (name "~" (effects (font (size 1.27 1.27))))
          (number "1" (effects (font (size 1.27 1.27))))
        )
        (pin passive line (at 5.08 0 180) (length 2.032)
          (name "~" (effects (font (size 1.27 1.27))))
          (number "2" (effects (font (size 1.27 1.27))))
        )
      )
    )
	(symbol "sdi-mipi-bridge:C_10u_0603" (pin_numbers hide) (pin_names hide) (in_bom yes) (on_board yes)
      (property "Reference" "C" (at 20.32 -5.08 0)
        (effects (font (size 1.27 1.27) (thickness 0.15)) (justify left bottom))
      )
      (property "Value" "C_10u_0603" (at 20.32 -10.16 0)
        (effects (font (size 1.27 1.27) (thickness 0.15)) (justify left bottom) hide)
      )
      (property "Footprint" "sdi-mipi-bridge-footprints:C_0603_1608Metric" (at 20.32 -12.7 0)
        (effects (font (size 1.27 1.27) (thickness 0.15)) (justify left bottom) hide)
      )
      (property "Datasheet" " " (at 20.32 -15.24 0)
        (effects (font (size 1.27 1.27) (thickness 0.15)) (justify left bottom) hide)
      )
      (property "MPN" "GRM188R61A106KE69D" (at 20.32 -17.78 0)
        (effects (font (size 1.27 1.27) (thickness 0.15)) (justify left bottom) hide)
      )
      (property "Manufacturer" "Murata" (at 20.32 -20.32 0)
        (effects (font (size 1.27 1.27) (thickness 0.15)) (justify left bottom) hide)
      )
      (property "License" "Apache-2.0" (at 20.32 -22.86 0)
        (effects (font (size 1.27 1.27) (thickness 0.15)) (justify left bottom) hide)
      )
      (property "Author" "Antmicro" (at 20.32 -25.4 0)
        (effects (font (size 1.27 1.27) (thickness 0.15)) (justify left bottom) hide)
      )
      (property "Val" "10u" (at 20.32 -7.62 0)
        (effects (font (size 1.27 1.27) (thickness 0.15)) (justify left bottom))
      )
      (property "Voltage" "" (at 20.32 -27.94 0)
        (effects (font (size 1.27 1.27)) (justify left bottom) hide)
      )
      (property "Dielectric" "template_dielectric" (at 20.32 -30.48 0)
        (effects (font (size 1.27 1.27)) (justify left bottom) hide)
      )
      (property "ki_description" " " (at 0 0 0)
        (effects (font (size 1.27 1.27)) hide)
      )
      (symbol "C_10u_0603_0_1"
        (polyline
          (pts
            (xy 2.032 -1.524)
            (xy 2.032 1.524)
          )
          (stroke (width 0.3048) (type default))
          (fill (type none))
        )
        (polyline
          (pts
            (xy 3.048 -1.524)
            (xy 3.048 1.524)
          )
          (stroke (width 0.3302) (type default))
          (fill (type none))
        )
      )
      (symbol "C_10u_0603_1_1"
        (pin passive line (at 0 0 0) (length 2.032)
          (name "~" (effects (font (size 1.27 1.27))))
          (number "1" (effects (font (size 1.27 1.27))))
        )
        (pin passive line (at 5.08 0 180) (length 2.032)
          (name "~" (effects (font (size 1.27 1.27))))
          (number "2" (effects (font (size 1.27 1.27))))
        )
      )
    )
	(symbol "sdi-mipi-bridge:C_16p_0402" (pin_numbers hide) (pin_names hide) (in_bom yes) (on_board yes)
      (property "Reference" "C" (at 20.32 -5.08 0)
        (effects (font (size 1.27 1.27) (thickness 0.15)) (justify left bottom))
      )
      (property "Value" "C_16p_0402" (at 20.32 -10.16 0)
        (effects (font (size 1.27 1.27) (thickness 0.15)) (justify left bottom) hide)
      )
      (property "Footprint" "sdi-mipi-bridge-footprints:C_0402_1005Metric" (at 20.32 -12.7 0)
        (effects (font (size 1.27 1.27) (thickness 0.15)) (justify left bottom) hide)
      )
      (property "Datasheet" " " (at 20.32 -15.24 0)
        (effects (font (size 1.27 1.27) (thickness 0.15)) (justify left bottom) hide)
      )
      (property "MPN" "0402N160J500CT" (at 20.32 -17.78 0)
        (effects (font (size 1.27 1.27) (thickness 0.15)) (justify left bottom) hide)
      )
      (property "Manufacturer" "Walsin" (at 20.32 -20.32 0)
        (effects (font (size 1.27 1.27) (thickness 0.15)) (justify left bottom) hide)
      )
      (property "License" "Apache-2.0" (at 20.32 -22.86 0)
        (effects (font (size 1.27 1.27) (thickness 0.15)) (justify left bottom) hide)
      )
      (property "Author" "Antmicro" (at 20.32 -25.4 0)
        (effects (font (size 1.27 1.27) (thickness 0.15)) (justify left bottom) hide)
      )
      (property "Val" "16p" (at 20.32 -7.62 0)
        (effects (font (size 1.27 1.27) (thickness 0.15)) (justify left bottom))
      )
      (property "Voltage" "" (at 20.32 -27.94 0)
        (effects (font (size 1.27 1.27)) (justify left bottom) hide)
      )
      (property "Dielectric" "" (at 20.32 -30.48 0)
        (effects (font (size 1.27 1.27)) (justify left bottom) hide)
      )
      (property "ki_description" " " (at 0 0 0)
        (effects (font (size 1.27 1.27)) hide)
      )
      (symbol "C_16p_0402_0_1"
        (polyline
          (pts
            (xy 2.032 -1.524)
            (xy 2.032 1.524)
          )
          (stroke (width 0.3048) (type default))
          (fill (type none))
        )
        (polyline
          (pts
            (xy 3.048 -1.524)
            (xy 3.048 1.524)
          )
          (stroke (width 0.3302) (type default))
          (fill (type none))
        )
      )
      (symbol "C_16p_0402_1_1"
        (pin passive line (at 0 0 0) (length 2.032)
          (name "~" (effects (font (size 1.27 1.27))))
          (number "1" (effects (font (size 1.27 1.27))))
        )
        (pin passive line (at 5.08 0 180) (length 2.032)
          (name "~" (effects (font (size 1.27 1.27))))
          (number "2" (effects (font (size 1.27 1.27))))
        )
      )
    )
	(symbol "sdi-mipi-bridge:C_1u_0402" (pin_numbers hide) (pin_names hide) (in_bom yes) (on_board yes)
      (property "Reference" "C" (at 20.32 -5.08 0)
        (effects (font (size 1.27 1.27) (thickness 0.15)) (justify left bottom))
      )
      (property "Value" "C_1u_0402" (at 20.32 -10.16 0)
        (effects (font (size 1.27 1.27) (thickness 0.15)) (justify left bottom) hide)
      )
      (property "Footprint" "sdi-mipi-bridge-footprints:C_0402_1005Metric" (at 20.32 -12.7 0)
        (effects (font (size 1.27 1.27) (thickness 0.15)) (justify left bottom) hide)
      )
      (property "Datasheet" " " (at 20.32 -15.24 0)
        (effects (font (size 1.27 1.27) (thickness 0.15)) (justify left bottom) hide)
      )
      (property "MPN" "C1005X6S1A105K050BC" (at 20.32 -17.78 0)
        (effects (font (size 1.27 1.27) (thickness 0.15)) (justify left bottom) hide)
      )
      (property "Manufacturer" "TDK" (at 20.32 -20.32 0)
        (effects (font (size 1.27 1.27) (thickness 0.15)) (justify left bottom) hide)
      )
      (property "License" "Apache-2.0" (at 20.32 -22.86 0)
        (effects (font (size 1.27 1.27) (thickness 0.15)) (justify left bottom) hide)
      )
      (property "Author" "Antmicro" (at 20.32 -25.4 0)
        (effects (font (size 1.27 1.27) (thickness 0.15)) (justify left bottom) hide)
      )
      (property "Val" "1u" (at 20.32 -7.62 0)
        (effects (font (size 1.27 1.27) (thickness 0.15)) (justify left bottom))
      )
      (property "Voltage" "" (at 20.32 -27.94 0)
        (effects (font (size 1.27 1.27)) (justify left bottom) hide)
      )
      (property "Dielectric" "" (at 20.32 -30.48 0)
        (effects (font (size 1.27 1.27)) (justify left bottom) hide)
      )
      (property "ki_description" " " (at 0 0 0)
        (effects (font (size 1.27 1.27)) hide)
      )
      (symbol "C_1u_0402_0_1"
        (polyline
          (pts
            (xy 2.032 -1.524)
            (xy 2.032 1.524)
          )
          (stroke (width 0.3048) (type default))
          (fill (type none))
        )
        (polyline
          (pts
            (xy 3.048 -1.524)
            (xy 3.048 1.524)
          )
          (stroke (width 0.3302) (type default))
          (fill (type none))
        )
      )
      (symbol "C_1u_0402_1_1"
        (pin passive line (at 0 0 0) (length 2.032)
          (name "~" (effects (font (size 1.27 1.27))))
          (number "1" (effects (font (size 1.27 1.27))))
        )
        (pin passive line (at 5.08 0 180) (length 2.032)
          (name "~" (effects (font (size 1.27 1.27))))
          (number "2" (effects (font (size 1.27 1.27))))
        )
      )
    )
	(symbol "sdi-mipi-bridge:C_1u_0402_10" (pin_numbers hide) (pin_names hide) (in_bom yes) (on_board yes)
      (property "Reference" "C" (at 20.32 -5.08 0)
        (effects (font (size 1.27 1.27) (thickness 0.15)) (justify left bottom))
      )
      (property "Value" "C_1u_0402_10" (at 20.32 -10.16 0)
        (effects (font (size 1.27 1.27) (thickness 0.15)) (justify left bottom) hide)
      )
      (property "Footprint" "sdi-mipi-bridge-footprints:C_0402_1005Metric" (at 20.32 -12.7 0)
        (effects (font (size 1.27 1.27) (thickness 0.15)) (justify left bottom) hide)
      )
      (property "Datasheet" " " (at 20.32 -15.24 0)
        (effects (font (size 1.27 1.27) (thickness 0.15)) (justify left bottom) hide)
      )
      (property "MPN" "C1005X6S1A105K050BC" (at 20.32 -17.78 0)
        (effects (font (size 1.27 1.27) (thickness 0.15)) (justify left bottom) hide)
      )
      (property "Manufacturer" "TDK" (at 20.32 -20.32 0)
        (effects (font (size 1.27 1.27) (thickness 0.15)) (justify left bottom) hide)
      )
      (property "License" "Apache-2.0" (at 20.32 -22.86 0)
        (effects (font (size 1.27 1.27) (thickness 0.15)) (justify left bottom) hide)
      )
      (property "Author" "Antmicro" (at 20.32 -25.4 0)
        (effects (font (size 1.27 1.27) (thickness 0.15)) (justify left bottom) hide)
      )
      (property "Val" "1u" (at 20.32 -7.62 0)
        (effects (font (size 1.27 1.27) (thickness 0.15)) (justify left bottom))
      )
      (property "Voltage" "" (at 20.32 -27.94 0)
        (effects (font (size 1.27 1.27)) (justify left bottom) hide)
      )
      (property "Dielectric" "" (at 20.32 -30.48 0)
        (effects (font (size 1.27 1.27)) (justify left bottom) hide)
      )
      (property "ki_description" " " (at 0 0 0)
        (effects (font (size 1.27 1.27)) hide)
      )
      (symbol "C_1u_0402_10_0_1"
        (polyline
          (pts
            (xy 2.032 -1.524)
            (xy 2.032 1.524)
          )
          (stroke (width 0.3048) (type default))
          (fill (type none))
        )
        (polyline
          (pts
            (xy 3.048 -1.524)
            (xy 3.048 1.524)
          )
          (stroke (width 0.3302) (type default))
          (fill (type none))
        )
      )
      (symbol "C_1u_0402_10_1_1"
        (pin passive line (at 0 0 0) (length 2.032)
          (name "~" (effects (font (size 1.27 1.27))))
          (number "1" (effects (font (size 1.27 1.27))))
        )
        (pin passive line (at 5.08 0 180) (length 2.032)
          (name "~" (effects (font (size 1.27 1.27))))
          (number "2" (effects (font (size 1.27 1.27))))
        )
      )
    )
	(symbol "sdi-mipi-bridge:C_1u_0402_11" (pin_numbers hide) (pin_names hide) (in_bom yes) (on_board yes)
      (property "Reference" "C" (at 20.32 -5.08 0)
        (effects (font (size 1.27 1.27) (thickness 0.15)) (justify left bottom))
      )
      (property "Value" "C_1u_0402_11" (at 20.32 -10.16 0)
        (effects (font (size 1.27 1.27) (thickness 0.15)) (justify left bottom) hide)
      )
      (property "Footprint" "sdi-mipi-bridge-footprints:C_0402_1005Metric" (at 20.32 -12.7 0)
        (effects (font (size 1.27 1.27) (thickness 0.15)) (justify left bottom) hide)
      )
      (property "Datasheet" " " (at 20.32 -15.24 0)
        (effects (font (size 1.27 1.27) (thickness 0.15)) (justify left bottom) hide)
      )
      (property "MPN" "C1005X6S1A105K050BC" (at 20.32 -17.78 0)
        (effects (font (size 1.27 1.27) (thickness 0.15)) (justify left bottom) hide)
      )
      (property "Manufacturer" "TDK" (at 20.32 -20.32 0)
        (effects (font (size 1.27 1.27) (thickness 0.15)) (justify left bottom) hide)
      )
      (property "License" "Apache-2.0" (at 20.32 -22.86 0)
        (effects (font (size 1.27 1.27) (thickness 0.15)) (justify left bottom) hide)
      )
      (property "Author" "Antmicro" (at 20.32 -25.4 0)
        (effects (font (size 1.27 1.27) (thickness 0.15)) (justify left bottom) hide)
      )
      (property "Val" "1u" (at 20.32 -7.62 0)
        (effects (font (size 1.27 1.27) (thickness 0.15)) (justify left bottom))
      )
      (property "Voltage" "" (at 20.32 -27.94 0)
        (effects (font (size 1.27 1.27)) (justify left bottom) hide)
      )
      (property "Dielectric" "" (at 20.32 -30.48 0)
        (effects (font (size 1.27 1.27)) (justify left bottom) hide)
      )
      (property "ki_description" " " (at 0 0 0)
        (effects (font (size 1.27 1.27)) hide)
      )
      (symbol "C_1u_0402_11_0_1"
        (polyline
          (pts
            (xy 2.032 -1.524)
            (xy 2.032 1.524)
          )
          (stroke (width 0.3048) (type default))
          (fill (type none))
        )
        (polyline
          (pts
            (xy 3.048 -1.524)
            (xy 3.048 1.524)
          )
          (stroke (width 0.3302) (type default))
          (fill (type none))
        )
      )
      (symbol "C_1u_0402_11_1_1"
        (pin passive line (at 0 0 0) (length 2.032)
          (name "~" (effects (font (size 1.27 1.27))))
          (number "1" (effects (font (size 1.27 1.27))))
        )
        (pin passive line (at 5.08 0 180) (length 2.032)
          (name "~" (effects (font (size 1.27 1.27))))
          (number "2" (effects (font (size 1.27 1.27))))
        )
      )
    )
	(symbol "sdi-mipi-bridge:C_2u2_0402" (pin_numbers hide) (pin_names hide) (in_bom yes) (on_board yes)
      (property "Reference" "C" (at 20.32 -5.08 0)
        (effects (font (size 1.27 1.27) (thickness 0.15)) (justify left bottom))
      )
      (property "Value" "C_2u2_0402" (at 20.32 -10.16 0)
        (effects (font (size 1.27 1.27) (thickness 0.15)) (justify left bottom) hide)
      )
      (property "Footprint" "sdi-mipi-bridge-footprints:C_0402_1005Metric" (at 20.32 -12.7 0)
        (effects (font (size 1.27 1.27) (thickness 0.15)) (justify left bottom) hide)
      )
      (property "Datasheet" " " (at 20.32 -15.24 0)
        (effects (font (size 1.27 1.27) (thickness 0.15)) (justify left bottom) hide)
      )
      (property "MPN" "C1005X5R1A225K050BC" (at 20.32 -17.78 0)
        (effects (font (size 1.27 1.27) (thickness 0.15)) (justify left bottom) hide)
      )
      (property "Manufacturer" "TDK" (at 20.32 -20.32 0)
        (effects (font (size 1.27 1.27) (thickness 0.15)) (justify left bottom) hide)
      )
      (property "License" "Apache-2.0" (at 20.32 -22.86 0)
        (effects (font (size 1.27 1.27) (thickness 0.15)) (justify left bottom) hide)
      )
      (property "Author" "Antmicro" (at 20.32 -25.4 0)
        (effects (font (size 1.27 1.27) (thickness 0.15)) (justify left bottom) hide)
      )
      (property "Val" "2u2" (at 20.32 -7.62 0)
        (effects (font (size 1.27 1.27) (thickness 0.15)) (justify left bottom))
      )
      (property "Voltage" "" (at 20.32 -27.94 0)
        (effects (font (size 1.27 1.27)) (justify left bottom) hide)
      )
      (property "Dielectric" "" (at 20.32 -30.48 0)
        (effects (font (size 1.27 1.27)) (justify left bottom) hide)
      )
      (property "ki_description" " " (at 0 0 0)
        (effects (font (size 1.27 1.27)) hide)
      )
      (symbol "C_2u2_0402_0_1"
        (polyline
          (pts
            (xy 2.032 -1.524)
            (xy 2.032 1.524)
          )
          (stroke (width 0.3048) (type default))
          (fill (type none))
        )
        (polyline
          (pts
            (xy 3.048 -1.524)
            (xy 3.048 1.524)
          )
          (stroke (width 0.3302) (type default))
          (fill (type none))
        )
      )
      (symbol "C_2u2_0402_1_1"
        (pin passive line (at 0 0 0) (length 2.032)
          (name "~" (effects (font (size 1.27 1.27))))
          (number "1" (effects (font (size 1.27 1.27))))
        )
        (pin passive line (at 5.08 0 180) (length 2.032)
          (name "~" (effects (font (size 1.27 1.27))))
          (number "2" (effects (font (size 1.27 1.27))))
        )
      )
    )
	(symbol "sdi-mipi-bridge:C_33u_0603" (pin_numbers hide) (pin_names hide) (in_bom yes) (on_board yes)
      (property "Reference" "C" (at 13.97 0 0)
        (effects (font (size 1.27 1.27) (thickness 0.15)) (justify left bottom))
      )
      (property "Value" "C_33u_0603" (at 13.97 -5.08 0)
        (effects (font (size 1.27 1.27) (thickness 0.15)) (justify left bottom) hide)
      )
      (property "Footprint" "sdi-mipi-bridge-footprints:C_0603_1608Metric" (at 13.97 -7.62 0)
        (effects (font (size 1.27 1.27) (thickness 0.15)) (justify left bottom) hide)
      )
      (property "Datasheet" " " (at 13.97 -10.16 0)
        (effects (font (size 1.27 1.27) (thickness 0.15)) (justify left bottom) hide)
      )
      (property "MPN" "F980G336MMA" (at 13.97 -12.7 0)
        (effects (font (size 1.27 1.27) (thickness 0.15)) (justify left bottom) hide)
      )
      (property "Manufacturer" "AVX" (at 13.97 -15.24 0)
        (effects (font (size 1.27 1.27) (thickness 0.15)) (justify left bottom) hide)
      )
      (property "License" "Apache-2.0" (at 13.97 -17.78 0)
        (effects (font (size 1.27 1.27) (thickness 0.15)) (justify left bottom) hide)
      )
      (property "Author" "Antmicro" (at 13.97 -20.32 0)
        (effects (font (size 1.27 1.27) (thickness 0.15)) (justify left bottom) hide)
      )
      (property "Val" "33u" (at 13.97 -2.54 0)
        (effects (font (size 1.27 1.27) (thickness 0.15)) (justify left bottom))
      )
      (property "Voltage" "" (at 13.97 -22.86 0)
        (effects (font (size 1.27 1.27)) (justify left bottom) hide)
      )
      (property "Dielectric" "" (at 13.97 -25.4 0)
        (effects (font (size 1.27 1.27)) (justify left bottom) hide)
      )
      (property "ki_description" " " (at 0 0 0)
        (effects (font (size 1.27 1.27)) hide)
      )
      (symbol "C_33u_0603_0_1"
        (rectangle (start -1.524 -2.921) (end 1.524 -3.302)
          (stroke (width 0) (type default))
          (fill (type outline))
        )
        (rectangle (start -1.524 -1.905) (end 1.524 -2.286)
          (stroke (width 0) (type default))
          (fill (type none))
        )
        (polyline
          (pts
            (xy -1.27 -0.9652)
            (xy -0.762 -0.9652)
          )
          (stroke (width 0) (type default))
          (fill (type none))
        )
        (polyline
          (pts
            (xy -1.016 -1.2192)
            (xy -1.016 -0.7112)
          )
          (stroke (width 0) (type default))
          (fill (type none))
        )
      )
      (symbol "C_33u_0603_1_1"
        (pin passive line (at 0 0 270) (length 1.8542)
          (name "~" (effects (font (size 1.27 1.27))))
          (number "1" (effects (font (size 1.27 1.27))))
        )
        (pin passive line (at 0 -5.08 90) (length 1.8542)
          (name "~" (effects (font (size 1.27 1.27))))
          (number "2" (effects (font (size 1.27 1.27))))
        )
      )
    )
	(symbol "sdi-mipi-bridge:C_470n_0402" (pin_numbers hide) (pin_names hide) (in_bom yes) (on_board yes)
      (property "Reference" "C" (at 20.32 -5.08 0)
        (effects (font (size 1.27 1.27) (thickness 0.15)) (justify left bottom))
      )
      (property "Value" "C_470n_0402" (at 20.32 -10.16 0)
        (effects (font (size 1.27 1.27) (thickness 0.15)) (justify left bottom) hide)
      )
      (property "Footprint" "sdi-mipi-bridge-footprints:C_0402_1005Metric" (at 20.32 -12.7 0)
        (effects (font (size 1.27 1.27) (thickness 0.15)) (justify left bottom) hide)
      )
      (property "Datasheet" " " (at 20.32 -15.24 0)
        (effects (font (size 1.27 1.27) (thickness 0.15)) (justify left bottom) hide)
      )
      (property "MPN" "C1005X5R1E474M050BB" (at 20.32 -17.78 0)
        (effects (font (size 1.27 1.27) (thickness 0.15)) (justify left bottom) hide)
      )
      (property "Manufacturer" "TDK" (at 20.32 -20.32 0)
        (effects (font (size 1.27 1.27) (thickness 0.15)) (justify left bottom) hide)
      )
      (property "License" "Apache-2.0" (at 20.32 -22.86 0)
        (effects (font (size 1.27 1.27) (thickness 0.15)) (justify left bottom) hide)
      )
      (property "Author" "Antmicro" (at 20.32 -25.4 0)
        (effects (font (size 1.27 1.27) (thickness 0.15)) (justify left bottom) hide)
      )
      (property "Val" "470n" (at 20.32 -7.62 0)
        (effects (font (size 1.27 1.27) (thickness 0.15)) (justify left bottom))
      )
      (property "Voltage" "" (at 20.32 -27.94 0)
        (effects (font (size 1.27 1.27)) (justify left bottom) hide)
      )
      (property "Dielectric" "" (at 20.32 -30.48 0)
        (effects (font (size 1.27 1.27)) (justify left bottom) hide)
      )
      (property "ki_description" " " (at 0 0 0)
        (effects (font (size 1.27 1.27)) hide)
      )
      (symbol "C_470n_0402_0_1"
        (polyline
          (pts
            (xy 2.032 -1.524)
            (xy 2.032 1.524)
          )
          (stroke (width 0.3048) (type default))
          (fill (type none))
        )
        (polyline
          (pts
            (xy 3.048 -1.524)
            (xy 3.048 1.524)
          )
          (stroke (width 0.3302) (type default))
          (fill (type none))
        )
      )
      (symbol "C_470n_0402_1_1"
        (pin passive line (at 0 0 0) (length 2.032)
          (name "~" (effects (font (size 1.27 1.27))))
          (number "1" (effects (font (size 1.27 1.27))))
        )
        (pin passive line (at 5.08 0 180) (length 2.032)
          (name "~" (effects (font (size 1.27 1.27))))
          (number "2" (effects (font (size 1.27 1.27))))
        )
      )
    )
	(symbol "sdi-mipi-bridge:C_47n_0402" (pin_numbers hide) (pin_names hide) (in_bom yes) (on_board yes)
      (property "Reference" "C" (at 20.32 -5.08 0)
        (effects (font (size 1.27 1.27) (thickness 0.15)) (justify left bottom))
      )
      (property "Value" "C_47n_0402" (at 20.32 -10.16 0)
        (effects (font (size 1.27 1.27) (thickness 0.15)) (justify left bottom) hide)
      )
      (property "Footprint" "sdi-mipi-bridge-footprints:C_0402_1005Metric" (at 20.32 -12.7 0)
        (effects (font (size 1.27 1.27) (thickness 0.15)) (justify left bottom) hide)
      )
      (property "Datasheet" " " (at 20.32 -15.24 0)
        (effects (font (size 1.27 1.27) (thickness 0.15)) (justify left bottom) hide)
      )
      (property "MPN" "MC0402X473K160CT" (at 20.32 -17.78 0)
        (effects (font (size 1.27 1.27) (thickness 0.15)) (justify left bottom) hide)
      )
      (property "Manufacturer" "Multicomp" (at 20.32 -20.32 0)
        (effects (font (size 1.27 1.27) (thickness 0.15)) (justify left bottom) hide)
      )
      (property "License" "Apache-2.0" (at 20.32 -22.86 0)
        (effects (font (size 1.27 1.27) (thickness 0.15)) (justify left bottom) hide)
      )
      (property "Author" "Antmicro" (at 20.32 -25.4 0)
        (effects (font (size 1.27 1.27) (thickness 0.15)) (justify left bottom) hide)
      )
      (property "Val" "47n" (at 20.32 -7.62 0)
        (effects (font (size 1.27 1.27) (thickness 0.15)) (justify left bottom))
      )
      (property "Voltage" "" (at 20.32 -27.94 0)
        (effects (font (size 1.27 1.27)) (justify left bottom) hide)
      )
      (property "Dielectric" "" (at 20.32 -30.48 0)
        (effects (font (size 1.27 1.27)) (justify left bottom) hide)
      )
      (property "ki_description" " " (at 0 0 0)
        (effects (font (size 1.27 1.27)) hide)
      )
      (symbol "C_47n_0402_0_1"
        (polyline
          (pts
            (xy 2.032 -1.524)
            (xy 2.032 1.524)
          )
          (stroke (width 0.3048) (type default))
          (fill (type none))
        )
        (polyline
          (pts
            (xy 3.048 -1.524)
            (xy 3.048 1.524)
          )
          (stroke (width 0.3302) (type default))
          (fill (type none))
        )
      )
      (symbol "C_47n_0402_1_1"
        (pin passive line (at 0 0 0) (length 2.032)
          (name "~" (effects (font (size 1.27 1.27))))
          (number "1" (effects (font (size 1.27 1.27))))
        )
        (pin passive line (at 5.08 0 180) (length 2.032)
          (name "~" (effects (font (size 1.27 1.27))))
          (number "2" (effects (font (size 1.27 1.27))))
        )
      )
    )
	(symbol "sdi-mipi-bridge:C_4u7_0402" (pin_numbers hide) (pin_names hide) (in_bom yes) (on_board yes)
      (property "Reference" "C" (at 20.32 -5.08 0)
        (effects (font (size 1.27 1.27) (thickness 0.15)) (justify left bottom))
      )
      (property "Value" "C_4u7_0402" (at 20.32 -10.16 0)
        (effects (font (size 1.27 1.27) (thickness 0.15)) (justify left bottom) hide)
      )
      (property "Footprint" "sdi-mipi-bridge-footprints:C_0402_1005Metric" (at 20.32 -12.7 0)
        (effects (font (size 1.27 1.27) (thickness 0.15)) (justify left bottom) hide)
      )
      (property "Datasheet" " " (at 20.32 -15.24 0)
        (effects (font (size 1.27 1.27) (thickness 0.15)) (justify left bottom) hide)
      )
      (property "MPN" "GRM155R61A475MEAAD" (at 20.32 -17.78 0)
        (effects (font (size 1.27 1.27) (thickness 0.15)) (justify left bottom) hide)
      )
      (property "Manufacturer" "Murata" (at 20.32 -20.32 0)
        (effects (font (size 1.27 1.27) (thickness 0.15)) (justify left bottom) hide)
      )
      (property "License" "Apache-2.0" (at 20.32 -22.86 0)
        (effects (font (size 1.27 1.27) (thickness 0.15)) (justify left bottom) hide)
      )
      (property "Author" "Antmicro" (at 20.32 -25.4 0)
        (effects (font (size 1.27 1.27) (thickness 0.15)) (justify left bottom) hide)
      )
      (property "Val" "4u7" (at 20.32 -7.62 0)
        (effects (font (size 1.27 1.27) (thickness 0.15)) (justify left bottom))
      )
      (property "Voltage" "" (at 20.32 -27.94 0)
        (effects (font (size 1.27 1.27)) (justify left bottom) hide)
      )
      (property "Dielectric" "" (at 20.32 -30.48 0)
        (effects (font (size 1.27 1.27)) (justify left bottom) hide)
      )
      (property "ki_description" " " (at 0 0 0)
        (effects (font (size 1.27 1.27)) hide)
      )
      (symbol "C_4u7_0402_0_1"
        (polyline
          (pts
            (xy 2.032 -1.524)
            (xy 2.032 1.524)
          )
          (stroke (width 0.3048) (type default))
          (fill (type none))
        )
        (polyline
          (pts
            (xy 3.048 -1.524)
            (xy 3.048 1.524)
          )
          (stroke (width 0.3302) (type default))
          (fill (type none))
        )
      )
      (symbol "C_4u7_0402_1_1"
        (pin passive line (at 0 0 0) (length 2.032)
          (name "~" (effects (font (size 1.27 1.27))))
          (number "1" (effects (font (size 1.27 1.27))))
        )
        (pin passive line (at 5.08 0 180) (length 2.032)
          (name "~" (effects (font (size 1.27 1.27))))
          (number "2" (effects (font (size 1.27 1.27))))
        )
      )
    )
	(symbol "sdi-mipi-bridge:C_5n6_0402" (pin_numbers hide) (pin_names hide) (in_bom yes) (on_board yes)
      (property "Reference" "C" (at 20.32 -5.08 0)
        (effects (font (size 1.27 1.27) (thickness 0.15)) (justify left bottom))
      )
      (property "Value" "C_5n6_0402" (at 20.32 -10.16 0)
        (effects (font (size 1.27 1.27) (thickness 0.15)) (justify left bottom) hide)
      )
      (property "Footprint" "sdi-mipi-bridge-footprints:C_0402_1005Metric" (at 20.32 -12.7 0)
        (effects (font (size 1.27 1.27) (thickness 0.15)) (justify left bottom) hide)
      )
      (property "Datasheet" " " (at 20.32 -15.24 0)
        (effects (font (size 1.27 1.27) (thickness 0.15)) (justify left bottom) hide)
      )
      (property "MPN" "MC0402B562K160CT" (at 20.32 -17.78 0)
        (effects (font (size 1.27 1.27) (thickness 0.15)) (justify left bottom) hide)
      )
      (property "Manufacturer" "Multicomp" (at 20.32 -20.32 0)
        (effects (font (size 1.27 1.27) (thickness 0.15)) (justify left bottom) hide)
      )
      (property "License" "Apache-2.0" (at 20.32 -22.86 0)
        (effects (font (size 1.27 1.27) (thickness 0.15)) (justify left bottom) hide)
      )
      (property "Author" "Antmicro" (at 20.32 -25.4 0)
        (effects (font (size 1.27 1.27) (thickness 0.15)) (justify left bottom) hide)
      )
      (property "Val" "5n6" (at 20.32 -7.62 0)
        (effects (font (size 1.27 1.27) (thickness 0.15)) (justify left bottom))
      )
      (property "Voltage" "" (at 20.32 -27.94 0)
        (effects (font (size 1.27 1.27)) (justify left bottom) hide)
      )
      (property "Dielectric" "" (at 20.32 -30.48 0)
        (effects (font (size 1.27 1.27)) (justify left bottom) hide)
      )
      (property "ki_description" " " (at 0 0 0)
        (effects (font (size 1.27 1.27)) hide)
      )
      (symbol "C_5n6_0402_0_1"
        (polyline
          (pts
            (xy 2.032 -1.524)
            (xy 2.032 1.524)
          )
          (stroke (width 0.3048) (type default))
          (fill (type none))
        )
        (polyline
          (pts
            (xy 3.048 -1.524)
            (xy 3.048 1.524)
          )
          (stroke (width 0.3302) (type default))
          (fill (type none))
        )
      )
      (symbol "C_5n6_0402_1_1"
        (pin passive line (at 0 0 0) (length 2.032)
          (name "~" (effects (font (size 1.27 1.27))))
          (number "1" (effects (font (size 1.27 1.27))))
        )
        (pin passive line (at 5.08 0 180) (length 2.032)
          (name "~" (effects (font (size 1.27 1.27))))
          (number "2" (effects (font (size 1.27 1.27))))
        )
      )
    )
	(symbol "sdi-mipi-bridge:C_6n2_0603" (pin_numbers hide) (pin_names hide) (in_bom yes) (on_board yes)
      (property "Reference" "C" (at 20.32 -5.08 0)
        (effects (font (size 1.27 1.27) (thickness 0.15)) (justify left bottom))
      )
      (property "Value" "C_6n2_0603" (at 20.32 -10.16 0)
        (effects (font (size 1.27 1.27) (thickness 0.15)) (justify left bottom) hide)
      )
      (property "Footprint" "sdi-mipi-bridge-footprints:C_0603_1608Metric" (at 20.32 -12.7 0)
        (effects (font (size 1.27 1.27) (thickness 0.15)) (justify left bottom) hide)
      )
      (property "Datasheet" " " (at 20.32 -15.24 0)
        (effects (font (size 1.27 1.27) (thickness 0.15)) (justify left bottom) hide)
      )
      (property "MPN" "C0603C622J5GACAUTO" (at 20.32 -17.78 0)
        (effects (font (size 1.27 1.27) (thickness 0.15)) (justify left bottom) hide)
      )
      (property "Manufacturer" "KEMET" (at 20.32 -20.32 0)
        (effects (font (size 1.27 1.27) (thickness 0.15)) (justify left bottom) hide)
      )
      (property "License" "Apache-2.0" (at 20.32 -22.86 0)
        (effects (font (size 1.27 1.27) (thickness 0.15)) (justify left bottom) hide)
      )
      (property "Author" "Antmicro" (at 20.32 -25.4 0)
        (effects (font (size 1.27 1.27) (thickness 0.15)) (justify left bottom) hide)
      )
      (property "Val" "6n2" (at 20.32 -7.62 0)
        (effects (font (size 1.27 1.27) (thickness 0.15)) (justify left bottom))
      )
      (property "Voltage" "" (at 20.32 -27.94 0)
        (effects (font (size 1.27 1.27)) (justify left bottom) hide)
      )
      (property "Dielectric" "" (at 20.32 -30.48 0)
        (effects (font (size 1.27 1.27)) (justify left bottom) hide)
      )
      (property "ki_description" " " (at 0 0 0)
        (effects (font (size 1.27 1.27)) hide)
      )
      (symbol "C_6n2_0603_0_1"
        (polyline
          (pts
            (xy 2.032 -1.524)
            (xy 2.032 1.524)
          )
          (stroke (width 0.3048) (type default))
          (fill (type none))
        )
        (polyline
          (pts
            (xy 3.048 -1.524)
            (xy 3.048 1.524)
          )
          (stroke (width 0.3302) (type default))
          (fill (type none))
        )
      )
      (symbol "C_6n2_0603_1_1"
        (pin passive line (at 0 0 0) (length 2.032)
          (name "~" (effects (font (size 1.27 1.27))))
          (number "1" (effects (font (size 1.27 1.27))))
        )
        (pin passive line (at 5.08 0 180) (length 2.032)
          (name "~" (effects (font (size 1.27 1.27))))
          (number "2" (effects (font (size 1.27 1.27))))
        )
      )
    )
	(symbol "sdi-mipi-bridge:Conn_BNC_031-70526-21" (pin_names hide) (in_bom yes) (on_board yes)
      (property "Reference" "J" (at 20.32 -5.08 0)
        (effects (font (size 1.27 1.27) (thickness 0.15)) (justify left bottom))
      )
      (property "Value" "Conn_BNC_031-70526-21" (at 20.32 -7.62 0)
        (effects (font (size 1.27 1.27) (thickness 0.15)) (justify left bottom))
      )
      (property "Footprint" "sdi-mipi-bridge-footprints:Conn_BNC_031-70526-21" (at 20.32 -10.16 0)
        (effects (font (size 1.27 1.27) (thickness 0.15)) (justify left bottom) hide)
      )
      (property "Datasheet" "https://www.farnell.com/cad/2305565.pdf?_ga=2.190633003.1014497200.1574067480-156563690.1566371002&_gac=1.57062104.1572875319.Cj0KCQiAtf_tBRDtARIsAIbAKe0A1M5y_jdFCiNLNrHM5L2GjmDvn_4qnRvhHAD9jBdL9AmoMNThLCoaAjhJEALw_wcB" (at 20.32 -12.7 0)
        (effects (font (size 1.27 1.27) (thickness 0.15)) (justify left bottom) hide)
      )
      (property "MPN" "031-70526-21" (at 20.32 -15.24 0)
        (effects (font (size 1.27 1.27) (thickness 0.15)) (justify left bottom) hide)
      )
      (property "Manufacturer" "Amphenol" (at 20.32 -17.78 0)
        (effects (font (size 1.27 1.27) (thickness 0.15)) (justify left bottom) hide)
      )
      (property "Author" "Antmicro" (at 20.32 -20.32 0)
        (effects (font (size 1.27 1.27) (thickness 0.15)) (justify left bottom) hide)
      )
      (property "License" "Apache-2.0" (at 20.32 -22.86 0)
        (effects (font (size 1.27 1.27) (thickness 0.15)) (justify left bottom) hide)
      )
      (property "ki_keywords" "HORIZONTAL, BULKHEAD, RF, CONNECTOR" (at 0 0 0)
        (effects (font (size 1.27 1.27)) hide)
      )
      (property "ki_description" "RF / Coaxial Connector, BNC Coaxial, Straight Bulkhead Jack, Board Edge / End Launch, 75 ohm" (at 0 0 0)
        (effects (font (size 1.27 1.27)) hide)
      )
      (property "ki_fp_filters" "*BNC* *SMA* *SMB* *SMC* *Cinch*" (at 0 0 0)
        (effects (font (size 1.27 1.27)) hide)
      )
      (symbol "Conn_BNC_031-70526-21_1_1"
        (polyline
          (pts
            (xy 2.54 0)
            (xy 4.572 0)
          )
          (stroke (width 0.254) (type default))
          (fill (type none))
        )
        (polyline
          (pts
            (xy 5.08 -2.54)
            (xy 5.08 -1.778)
          )
          (stroke (width 0.254) (type default))
          (fill (type none))
        )
        (arc (start 3.302 -0.508) (mid 5.302 -1.808) (end 6.858 0)
          (stroke (width 0.254) (type default))
          (fill (type none))
        )
        (circle (center 5.08 0) (radius 0.508)
          (stroke (width 0.254) (type default))
          (fill (type none))
        )
        (arc (start 6.858 0) (mid 5.302 1.8083) (end 3.302 0.508)
          (stroke (width 0.254) (type default))
          (fill (type none))
        )
        (pin passive line (at 0 0 0) (length 2.54)
          (name "1" (effects (font (size 1.27 1.27))))
          (number "1" (effects (font (size 1.27 1.27))))
        )
        (pin passive line (at 5.08 -5.08 90) (length 2.54)
          (name "2" (effects (font (size 1.27 1.27))))
          (number "2" (effects (font (size 1.27 1.27))))
        )
      )
    )
	(symbol "sdi-mipi-bridge:Conn_FFC_68715014522_ONE-SIDE" (pin_names hide) (in_bom yes) (on_board yes)
      (property "Reference" "J" (at 19.05 -5.08 0)
        (effects (font (size 1.27 1.27) (thickness 0.15)) (justify left bottom))
      )
      (property "Value" "Conn_FFC_68715014522_ONE-SIDE" (at 19.05 -7.62 0)
        (effects (font (size 1.27 1.27) (thickness 0.15)) (justify left bottom))
      )
      (property "Footprint" "sdi-mipi-bridge-footprints:WE_68715014522_ONE-SIDE" (at 19.05 -10.16 0)
        (effects (font (size 1.27 1.27) (thickness 0.15)) (justify left bottom) hide)
      )
      (property "Datasheet" "https://www.we-online.com/components/products/datasheet/68715014522.pdf" (at 19.05 -12.7 0)
        (effects (font (size 1.27 1.27) (thickness 0.15)) (justify left bottom) hide)
      )
      (property "MPN" "68715014522" (at 19.05 -15.24 0)
        (effects (font (size 1.27 1.27) (thickness 0.15)) (justify left bottom) hide)
      )
      (property "Manufacturer" "Würth Elektronik" (at 19.05 -17.78 0)
        (effects (font (size 1.27 1.27) (thickness 0.15)) (justify left bottom) hide)
      )
      (property "Author" "Antmicro" (at 19.05 -20.32 0)
        (effects (font (size 1.27 1.27) (thickness 0.15)) (justify left bottom) hide)
      )
      (property "License" "Apache-2.0" (at 19.05 -22.86 0)
        (effects (font (size 1.27 1.27) (thickness 0.15)) (justify left bottom) hide)
      )
      (symbol "Conn_FFC_68715014522_ONE-SIDE_1_1"
        (rectangle (start 2.54 -124.333) (end 3.81 -124.587)
          (stroke (width 0.254) (type default))
          (fill (type background))
        )
        (rectangle (start 2.54 -121.793) (end 3.81 -122.047)
          (stroke (width 0.254) (type default))
          (fill (type background))
        )
        (rectangle (start 2.54 -119.253) (end 3.81 -119.507)
          (stroke (width 0.254) (type default))
          (fill (type background))
        )
        (rectangle (start 2.54 -116.713) (end 3.81 -116.967)
          (stroke (width 0.254) (type default))
          (fill (type background))
        )
        (rectangle (start 2.54 -114.173) (end 3.81 -114.427)
          (stroke (width 0.254) (type default))
          (fill (type background))
        )
        (rectangle (start 2.54 -111.633) (end 3.81 -111.887)
          (stroke (width 0.254) (type default))
          (fill (type background))
        )
        (rectangle (start 2.54 -109.093) (end 3.81 -109.347)
          (stroke (width 0.254) (type default))
          (fill (type background))
        )
        (rectangle (start 2.54 -106.553) (end 3.81 -106.807)
          (stroke (width 0.254) (type default))
          (fill (type background))
        )
        (rectangle (start 2.54 -104.013) (end 3.81 -104.267)
          (stroke (width 0.254) (type default))
          (fill (type background))
        )
        (rectangle (start 2.54 -101.473) (end 3.81 -101.727)
          (stroke (width 0.254) (type default))
          (fill (type background))
        )
        (rectangle (start 2.54 -98.933) (end 3.81 -99.187)
          (stroke (width 0.254) (type default))
          (fill (type background))
        )
        (rectangle (start 2.54 -96.393) (end 3.81 -96.647)
          (stroke (width 0.254) (type default))
          (fill (type background))
        )
        (rectangle (start 2.54 -93.853) (end 3.81 -94.107)
          (stroke (width 0.254) (type default))
          (fill (type background))
        )
        (rectangle (start 2.54 -91.313) (end 3.81 -91.567)
          (stroke (width 0.254) (type default))
          (fill (type background))
        )
        (rectangle (start 2.54 -88.773) (end 3.81 -89.027)
          (stroke (width 0.254) (type default))
          (fill (type background))
        )
        (rectangle (start 2.54 -86.233) (end 3.81 -86.487)
          (stroke (width 0.254) (type default))
          (fill (type background))
        )
        (rectangle (start 2.54 -83.693) (end 3.81 -83.947)
          (stroke (width 0.254) (type default))
          (fill (type background))
        )
        (rectangle (start 2.54 -81.153) (end 3.81 -81.407)
          (stroke (width 0.254) (type default))
          (fill (type background))
        )
        (rectangle (start 2.54 -78.613) (end 3.81 -78.867)
          (stroke (width 0.254) (type default))
          (fill (type background))
        )
        (rectangle (start 2.54 -76.073) (end 3.81 -76.327)
          (stroke (width 0.254) (type default))
          (fill (type background))
        )
        (rectangle (start 2.54 -73.533) (end 3.81 -73.787)
          (stroke (width 0.254) (type default))
          (fill (type background))
        )
        (rectangle (start 2.54 -70.993) (end 3.81 -71.247)
          (stroke (width 0.254) (type default))
          (fill (type background))
        )
        (rectangle (start 2.54 -68.453) (end 3.81 -68.707)
          (stroke (width 0.254) (type default))
          (fill (type background))
        )
        (rectangle (start 2.54 -65.913) (end 3.81 -66.167)
          (stroke (width 0.254) (type default))
          (fill (type background))
        )
        (rectangle (start 2.54 -63.373) (end 3.81 -63.627)
          (stroke (width 0.254) (type default))
          (fill (type background))
        )
        (rectangle (start 2.54 -60.833) (end 3.81 -61.087)
          (stroke (width 0.254) (type default))
          (fill (type background))
        )
        (rectangle (start 2.54 -58.293) (end 3.81 -58.547)
          (stroke (width 0.254) (type default))
          (fill (type background))
        )
        (rectangle (start 2.54 -55.753) (end 3.81 -56.007)
          (stroke (width 0.254) (type default))
          (fill (type background))
        )
        (rectangle (start 2.54 -53.213) (end 3.81 -53.467)
          (stroke (width 0.254) (type default))
          (fill (type background))
        )
        (rectangle (start 2.54 -50.673) (end 3.81 -50.927)
          (stroke (width 0.254) (type default))
          (fill (type background))
        )
        (rectangle (start 2.54 -48.133) (end 3.81 -48.387)
          (stroke (width 0.254) (type default))
          (fill (type background))
        )
        (rectangle (start 2.54 -45.593) (end 3.81 -45.847)
          (stroke (width 0.254) (type default))
          (fill (type background))
        )
        (rectangle (start 2.54 -43.053) (end 3.81 -43.307)
          (stroke (width 0.254) (type default))
          (fill (type background))
        )
        (rectangle (start 2.54 -40.513) (end 3.81 -40.767)
          (stroke (width 0.254) (type default))
          (fill (type background))
        )
        (rectangle (start 2.54 -37.973) (end 3.81 -38.227)
          (stroke (width 0.254) (type default))
          (fill (type background))
        )
        (rectangle (start 2.54 -35.433) (end 3.81 -35.687)
          (stroke (width 0.254) (type default))
          (fill (type background))
        )
        (rectangle (start 2.54 -32.893) (end 3.81 -33.147)
          (stroke (width 0.254) (type default))
          (fill (type background))
        )
        (rectangle (start 2.54 -30.353) (end 3.81 -30.607)
          (stroke (width 0.254) (type default))
          (fill (type background))
        )
        (rectangle (start 2.54 -27.813) (end 3.81 -28.067)
          (stroke (width 0.254) (type default))
          (fill (type background))
        )
        (rectangle (start 2.54 -25.273) (end 3.81 -25.527)
          (stroke (width 0.254) (type default))
          (fill (type background))
        )
        (rectangle (start 2.54 -22.733) (end 3.81 -22.987)
          (stroke (width 0.254) (type default))
          (fill (type background))
        )
        (rectangle (start 2.54 -20.193) (end 3.81 -20.447)
          (stroke (width 0.254) (type default))
          (fill (type background))
        )
        (rectangle (start 2.54 -17.653) (end 3.81 -17.907)
          (stroke (width 0.254) (type default))
          (fill (type background))
        )
        (rectangle (start 2.54 -15.113) (end 3.81 -15.367)
          (stroke (width 0.254) (type default))
          (fill (type background))
        )
        (rectangle (start 2.54 -12.573) (end 3.81 -12.827)
          (stroke (width 0.254) (type default))
          (fill (type background))
        )
        (rectangle (start 2.54 -10.033) (end 3.81 -10.287)
          (stroke (width 0.254) (type default))
          (fill (type background))
        )
        (rectangle (start 2.54 -7.493) (end 3.81 -7.747)
          (stroke (width 0.254) (type default))
          (fill (type background))
        )
        (rectangle (start 2.54 -4.953) (end 3.81 -5.207)
          (stroke (width 0.254) (type default))
          (fill (type background))
        )
        (rectangle (start 2.54 -2.413) (end 3.81 -2.667)
          (stroke (width 0.254) (type default))
          (fill (type background))
        )
        (rectangle (start 2.54 0.127) (end 3.81 -0.127)
          (stroke (width 0.254) (type default))
          (fill (type background))
        )
        (rectangle (start 2.54 1.27) (end 5.08 -128.27)
          (stroke (width 0.254) (type default))
          (fill (type background))
        )
        (pin passive line (at 0 0 0) (length 2.54)
          (name "~" (effects (font (size 1.27 1.27))))
          (number "1" (effects (font (size 1.27 1.27))))
        )
        (pin passive line (at 0 -22.86 0) (length 2.54)
          (name "~" (effects (font (size 1.27 1.27))))
          (number "10" (effects (font (size 1.27 1.27))))
        )
        (pin passive line (at 0 -25.4 0) (length 2.54)
          (name "~" (effects (font (size 1.27 1.27))))
          (number "11" (effects (font (size 1.27 1.27))))
        )
        (pin passive line (at 0 -27.94 0) (length 2.54)
          (name "~" (effects (font (size 1.27 1.27))))
          (number "12" (effects (font (size 1.27 1.27))))
        )
        (pin passive line (at 0 -30.48 0) (length 2.54)
          (name "~" (effects (font (size 1.27 1.27))))
          (number "13" (effects (font (size 1.27 1.27))))
        )
        (pin passive line (at 0 -33.02 0) (length 2.54)
          (name "~" (effects (font (size 1.27 1.27))))
          (number "14" (effects (font (size 1.27 1.27))))
        )
        (pin passive line (at 0 -35.56 0) (length 2.54)
          (name "~" (effects (font (size 1.27 1.27))))
          (number "15" (effects (font (size 1.27 1.27))))
        )
        (pin passive line (at 0 -38.1 0) (length 2.54)
          (name "~" (effects (font (size 1.27 1.27))))
          (number "16" (effects (font (size 1.27 1.27))))
        )
        (pin passive line (at 0 -40.64 0) (length 2.54)
          (name "~" (effects (font (size 1.27 1.27))))
          (number "17" (effects (font (size 1.27 1.27))))
        )
        (pin passive line (at 0 -43.18 0) (length 2.54)
          (name "~" (effects (font (size 1.27 1.27))))
          (number "18" (effects (font (size 1.27 1.27))))
        )
        (pin passive line (at 0 -45.72 0) (length 2.54)
          (name "~" (effects (font (size 1.27 1.27))))
          (number "19" (effects (font (size 1.27 1.27))))
        )
        (pin passive line (at 0 -2.54 0) (length 2.54)
          (name "~" (effects (font (size 1.27 1.27))))
          (number "2" (effects (font (size 1.27 1.27))))
        )
        (pin passive line (at 0 -48.26 0) (length 2.54)
          (name "~" (effects (font (size 1.27 1.27))))
          (number "20" (effects (font (size 1.27 1.27))))
        )
        (pin passive line (at 0 -50.8 0) (length 2.54)
          (name "~" (effects (font (size 1.27 1.27))))
          (number "21" (effects (font (size 1.27 1.27))))
        )
        (pin passive line (at 0 -53.34 0) (length 2.54)
          (name "~" (effects (font (size 1.27 1.27))))
          (number "22" (effects (font (size 1.27 1.27))))
        )
        (pin passive line (at 0 -55.88 0) (length 2.54)
          (name "~" (effects (font (size 1.27 1.27))))
          (number "23" (effects (font (size 1.27 1.27))))
        )
        (pin passive line (at 0 -58.42 0) (length 2.54)
          (name "~" (effects (font (size 1.27 1.27))))
          (number "24" (effects (font (size 1.27 1.27))))
        )
        (pin passive line (at 0 -60.96 0) (length 2.54)
          (name "~" (effects (font (size 1.27 1.27))))
          (number "25" (effects (font (size 1.27 1.27))))
        )
        (pin passive line (at 0 -63.5 0) (length 2.54)
          (name "~" (effects (font (size 1.27 1.27))))
          (number "26" (effects (font (size 1.27 1.27))))
        )
        (pin passive line (at 0 -66.04 0) (length 2.54)
          (name "~" (effects (font (size 1.27 1.27))))
          (number "27" (effects (font (size 1.27 1.27))))
        )
        (pin passive line (at 0 -68.58 0) (length 2.54)
          (name "~" (effects (font (size 1.27 1.27))))
          (number "28" (effects (font (size 1.27 1.27))))
        )
        (pin passive line (at 0 -71.12 0) (length 2.54)
          (name "~" (effects (font (size 1.27 1.27))))
          (number "29" (effects (font (size 1.27 1.27))))
        )
        (pin passive line (at 0 -5.08 0) (length 2.54)
          (name "~" (effects (font (size 1.27 1.27))))
          (number "3" (effects (font (size 1.27 1.27))))
        )
        (pin passive line (at 0 -73.66 0) (length 2.54)
          (name "~" (effects (font (size 1.27 1.27))))
          (number "30" (effects (font (size 1.27 1.27))))
        )
        (pin passive line (at 0 -76.2 0) (length 2.54)
          (name "~" (effects (font (size 1.27 1.27))))
          (number "31" (effects (font (size 1.27 1.27))))
        )
        (pin passive line (at 0 -78.74 0) (length 2.54)
          (name "~" (effects (font (size 1.27 1.27))))
          (number "32" (effects (font (size 1.27 1.27))))
        )
        (pin passive line (at 0 -81.28 0) (length 2.54)
          (name "~" (effects (font (size 1.27 1.27))))
          (number "33" (effects (font (size 1.27 1.27))))
        )
        (pin passive line (at 0 -83.82 0) (length 2.54)
          (name "~" (effects (font (size 1.27 1.27))))
          (number "34" (effects (font (size 1.27 1.27))))
        )
        (pin passive line (at 0 -86.36 0) (length 2.54)
          (name "~" (effects (font (size 1.27 1.27))))
          (number "35" (effects (font (size 1.27 1.27))))
        )
        (pin passive line (at 0 -88.9 0) (length 2.54)
          (name "~" (effects (font (size 1.27 1.27))))
          (number "36" (effects (font (size 1.27 1.27))))
        )
        (pin passive line (at 0 -91.44 0) (length 2.54)
          (name "~" (effects (font (size 1.27 1.27))))
          (number "37" (effects (font (size 1.27 1.27))))
        )
        (pin passive line (at 0 -93.98 0) (length 2.54)
          (name "~" (effects (font (size 1.27 1.27))))
          (number "38" (effects (font (size 1.27 1.27))))
        )
        (pin passive line (at 0 -96.52 0) (length 2.54)
          (name "~" (effects (font (size 1.27 1.27))))
          (number "39" (effects (font (size 1.27 1.27))))
        )
        (pin passive line (at 0 -7.62 0) (length 2.54)
          (name "~" (effects (font (size 1.27 1.27))))
          (number "4" (effects (font (size 1.27 1.27))))
        )
        (pin passive line (at 0 -99.06 0) (length 2.54)
          (name "~" (effects (font (size 1.27 1.27))))
          (number "40" (effects (font (size 1.27 1.27))))
        )
        (pin passive line (at 0 -101.6 0) (length 2.54)
          (name "~" (effects (font (size 1.27 1.27))))
          (number "41" (effects (font (size 1.27 1.27))))
        )
        (pin passive line (at 0 -104.14 0) (length 2.54)
          (name "~" (effects (font (size 1.27 1.27))))
          (number "42" (effects (font (size 1.27 1.27))))
        )
        (pin passive line (at 0 -106.68 0) (length 2.54)
          (name "~" (effects (font (size 1.27 1.27))))
          (number "43" (effects (font (size 1.27 1.27))))
        )
        (pin passive line (at 0 -109.22 0) (length 2.54)
          (name "~" (effects (font (size 1.27 1.27))))
          (number "44" (effects (font (size 1.27 1.27))))
        )
        (pin passive line (at 0 -111.76 0) (length 2.54)
          (name "~" (effects (font (size 1.27 1.27))))
          (number "45" (effects (font (size 1.27 1.27))))
        )
        (pin passive line (at 0 -114.3 0) (length 2.54)
          (name "~" (effects (font (size 1.27 1.27))))
          (number "46" (effects (font (size 1.27 1.27))))
        )
        (pin passive line (at 0 -116.84 0) (length 2.54)
          (name "~" (effects (font (size 1.27 1.27))))
          (number "47" (effects (font (size 1.27 1.27))))
        )
        (pin passive line (at 0 -119.38 0) (length 2.54)
          (name "~" (effects (font (size 1.27 1.27))))
          (number "48" (effects (font (size 1.27 1.27))))
        )
        (pin passive line (at 0 -121.92 0) (length 2.54)
          (name "~" (effects (font (size 1.27 1.27))))
          (number "49" (effects (font (size 1.27 1.27))))
        )
        (pin passive line (at 0 -10.16 0) (length 2.54)
          (name "~" (effects (font (size 1.27 1.27))))
          (number "5" (effects (font (size 1.27 1.27))))
        )
        (pin passive line (at 0 -124.46 0) (length 2.54)
          (name "~" (effects (font (size 1.27 1.27))))
          (number "50" (effects (font (size 1.27 1.27))))
        )
        (pin passive line (at 0 -12.7 0) (length 2.54)
          (name "~" (effects (font (size 1.27 1.27))))
          (number "6" (effects (font (size 1.27 1.27))))
        )
        (pin passive line (at 0 -15.24 0) (length 2.54)
          (name "~" (effects (font (size 1.27 1.27))))
          (number "7" (effects (font (size 1.27 1.27))))
        )
        (pin passive line (at 0 -17.78 0) (length 2.54)
          (name "~" (effects (font (size 1.27 1.27))))
          (number "8" (effects (font (size 1.27 1.27))))
        )
        (pin passive line (at 0 -20.32 0) (length 2.54)
          (name "~" (effects (font (size 1.27 1.27))))
          (number "9" (effects (font (size 1.27 1.27))))
        )
        (pin passive line (at 0 -127 0) (length 2.54)
          (name "~" (effects (font (size 1.27 1.27))))
          (number "SH" (effects (font (size 1.27 1.27))))
        )
      )
    )
	(symbol "sdi-mipi-bridge:CrossLink_LIF-MD6000-6JMG80I" (in_bom yes) (on_board yes)
      (property "Reference" "U" (at 78.74 -6.35 0)
        (effects (font (size 1.27 1.27) (thickness 0.15)) (justify left bottom))
      )
      (property "Value" "CrossLink_LIF-MD6000-6JMG80I" (at 78.74 -11.43 0)
        (effects (font (size 1.27 1.27) (thickness 0.15)) (justify left bottom) hide)
      )
      (property "Footprint" "sdi-mipi-bridge-footprints:BGA-80_7x7mm_Layout10x10_P0.65mm" (at 78.74 -13.97 0)
        (effects (font (size 1.27 1.27) (thickness 0.15)) (justify left bottom) hide)
      )
      (property "Datasheet" "https://www.latticesemi.com/view_document?document_id=51662" (at 78.74 -16.51 0)
        (effects (font (size 1.27 1.27) (thickness 0.15)) (justify left bottom) hide)
      )
      (property "MPN" "LIF-MD6000-6JMG80I" (at 78.74 -8.89 0)
        (effects (font (size 1.27 1.27) (thickness 0.15)) (justify left bottom))
      )
      (property "Manufacturer" "Lattice Semiconductor" (at 78.74 -19.05 0)
        (effects (font (size 1.27 1.27) (thickness 0.15)) (justify left bottom) hide)
      )
      (property "Author" "Antmicro" (at 78.74 -21.59 0)
        (effects (font (size 1.27 1.27) (thickness 0.15)) (justify left bottom) hide)
      )
      (property "License" "Apache-2.0" (at 78.74 -24.13 0)
        (effects (font (size 1.27 1.27) (thickness 0.15)) (justify left bottom) hide)
      )
      (property "ki_keywords" "SMT, FPGA, IC" (at 0 0 0)
        (effects (font (size 1.27 1.27)) hide)
      )
      (property "ki_description" "FPGA, CrossLink, PLL37 I/O, 400 MHz, 5936 Cells, 1.14 V to 1.26 V, CTFBGA-80" (at 0 0 0)
        (effects (font (size 1.27 1.27)) hide)
      )
      (symbol "CrossLink_LIF-MD6000-6JMG80I_1_1"
        (polyline
          (pts
            (xy 25.4 -66.04)
            (xy 25.4 -110.49)
          )
          (stroke (width 0.254) (type default))
          (fill (type background))
        )
        (polyline
          (pts
            (xy 25.4 -22.86)
            (xy 25.4 -62.23)
          )
          (stroke (width 0.254) (type default))
          (fill (type background))
        )
        (polyline
          (pts
            (xy 31.75 -20.32)
            (xy 31.75 1.27)
          )
          (stroke (width 0.254) (type default))
          (fill (type background))
        )
        (polyline
          (pts
            (xy 44.45 -53.34)
            (xy 44.45 -85.09)
          )
          (stroke (width 0.254) (type default))
          (fill (type background))
        )
        (polyline
          (pts
            (xy 44.45 -46.99)
            (xy 44.45 -15.24)
          )
          (stroke (width 0.254) (type default))
          (fill (type background))
        )
        (rectangle (start 3.81 2.54) (end 59.69 -111.76)
          (stroke (width 0.254) (type default))
          (fill (type background))
        )
        (text "Bank_0" (at 34.29 -5.08 900)
          (effects (font (size 1.27 1.27) (thickness 0.15)) (justify left bottom))
        )
        (text "Bank_1" (at 27.94 -30.48 900)
          (effects (font (size 1.27 1.27) (thickness 0.15)) (justify left bottom))
        )
        (text "Bank_2" (at 27.94 -73.66 900)
          (effects (font (size 1.27 1.27) (thickness 0.15)) (justify left bottom))
        )
        (text "DPHY0" (at 44.45 -46.99 900)
          (effects (font (size 1.27 1.27) (thickness 0.15)) (justify left bottom))
        )
        (text "DPHY1" (at 44.45 -85.09 900)
          (effects (font (size 1.27 1.27) (thickness 0.15)) (justify left bottom))
        )
        (pin bidirectional line (at 63.5 -71.12 180) (length 3.81)
          (name "DPHY1_DN2" (effects (font (size 1.27 1.27))))
          (number "A1" (effects (font (size 1.27 1.27))))
        )
        (pin bidirectional line (at 63.5 -38.1 180) (length 3.81)
          (name "DPHY0_DN3" (effects (font (size 1.27 1.27))))
          (number "A10" (effects (font (size 1.27 1.27))))
        )
        (pin bidirectional line (at 63.5 -60.96 180) (length 3.81)
          (name "DPHY1_DN0" (effects (font (size 1.27 1.27))))
          (number "A2" (effects (font (size 1.27 1.27))))
        )
        (pin bidirectional line (at 63.5 -55.88 180) (length 3.81)
          (name "DPHY1_CKN" (effects (font (size 1.27 1.27))))
          (number "A3" (effects (font (size 1.27 1.27))))
        )
        (pin bidirectional line (at 63.5 -66.04 180) (length 3.81)
          (name "DPHY1_DN1" (effects (font (size 1.27 1.27))))
          (number "A4" (effects (font (size 1.27 1.27))))
        )
        (pin bidirectional line (at 63.5 -76.2 180) (length 3.81)
          (name "DPHY1_DN3" (effects (font (size 1.27 1.27))))
          (number "A5" (effects (font (size 1.27 1.27))))
        )
        (pin bidirectional line (at 63.5 -33.02 180) (length 3.81)
          (name "DPHY0_DN2" (effects (font (size 1.27 1.27))))
          (number "A6" (effects (font (size 1.27 1.27))))
        )
        (pin bidirectional line (at 63.5 -22.86 180) (length 3.81)
          (name "DPHY0_DN0" (effects (font (size 1.27 1.27))))
          (number "A7" (effects (font (size 1.27 1.27))))
        )
        (pin bidirectional line (at 63.5 -17.78 180) (length 3.81)
          (name "DPHY0_CKN" (effects (font (size 1.27 1.27))))
          (number "A8" (effects (font (size 1.27 1.27))))
        )
        (pin bidirectional line (at 63.5 -27.94 180) (length 3.81)
          (name "DPHY0_DN1" (effects (font (size 1.27 1.27))))
          (number "A9" (effects (font (size 1.27 1.27))))
        )
        (pin bidirectional line (at 63.5 -68.58 180) (length 3.81)
          (name "DPHY1_DP2" (effects (font (size 1.27 1.27))))
          (number "B1" (effects (font (size 1.27 1.27))))
        )
        (pin bidirectional line (at 63.5 -35.56 180) (length 3.81)
          (name "DPHY0_DP3" (effects (font (size 1.27 1.27))))
          (number "B10" (effects (font (size 1.27 1.27))))
        )
        (pin bidirectional line (at 63.5 -58.42 180) (length 3.81)
          (name "DPHY1_DP0" (effects (font (size 1.27 1.27))))
          (number "B2" (effects (font (size 1.27 1.27))))
        )
        (pin bidirectional line (at 63.5 -53.34 180) (length 3.81)
          (name "DPHY1_CKP" (effects (font (size 1.27 1.27))))
          (number "B3" (effects (font (size 1.27 1.27))))
        )
        (pin bidirectional line (at 63.5 -63.5 180) (length 3.81)
          (name "DPHY1_DP1" (effects (font (size 1.27 1.27))))
          (number "B4" (effects (font (size 1.27 1.27))))
        )
        (pin bidirectional line (at 63.5 -73.66 180) (length 3.81)
          (name "DPHY1_DP3" (effects (font (size 1.27 1.27))))
          (number "B5" (effects (font (size 1.27 1.27))))
        )
        (pin bidirectional line (at 63.5 -30.48 180) (length 3.81)
          (name "DPHY0_DP2" (effects (font (size 1.27 1.27))))
          (number "B6" (effects (font (size 1.27 1.27))))
        )
        (pin bidirectional line (at 63.5 -20.32 180) (length 3.81)
          (name "DPHY0_DP0" (effects (font (size 1.27 1.27))))
          (number "B7" (effects (font (size 1.27 1.27))))
        )
        (pin bidirectional line (at 63.5 -15.24 180) (length 3.81)
          (name "DPHY0_CKP" (effects (font (size 1.27 1.27))))
          (number "B8" (effects (font (size 1.27 1.27))))
        )
        (pin bidirectional line (at 63.5 -25.4 180) (length 3.81)
          (name "DPHY0_DP1" (effects (font (size 1.27 1.27))))
          (number "B9" (effects (font (size 1.27 1.27))))
        )
        (pin power_in line (at 63.5 -106.68 180) (length 3.81)
          (name "GND" (effects (font (size 1.27 1.27))))
          (number "C1" (effects (font (size 1.27 1.27))))
        )
        (pin passive line (at 63.5 -106.68 180) (length 3.81) hide
          (name "GND" (effects (font (size 1.27 1.27))))
          (number "C10" (effects (font (size 1.27 1.27))))
        )
        (pin power_in line (at 63.5 -78.74 180) (length 3.81)
          (name "GNDA_DPHY1" (effects (font (size 1.27 1.27))))
          (number "C2" (effects (font (size 1.27 1.27))))
        )
        (pin power_in line (at 63.5 -40.64 180) (length 3.81)
          (name "GNDA_DPHY0" (effects (font (size 1.27 1.27))))
          (number "C9" (effects (font (size 1.27 1.27))))
        )
        (pin bidirectional line (at 0 -5.08 0) (length 3.81)
          (name "PB48/PCLKT0_1/USER_SCL" (effects (font (size 1.27 1.27))))
          (number "D1" (effects (font (size 1.27 1.27))))
        )
        (pin bidirectional line (at 0 -71.12 0) (length 3.81)
          (name "PB16B/PCLKC2_0" (effects (font (size 1.27 1.27))))
          (number "D10" (effects (font (size 1.27 1.27))))
        )
        (pin power_in line (at 63.5 -83.82 180) (length 3.81)
          (name "VCCPLL_DPHY1" (effects (font (size 1.27 1.27))))
          (number "D2" (effects (font (size 1.27 1.27))))
        )
        (pin power_in line (at 63.5 -81.28 180) (length 3.81)
          (name "VCCA_DPHY1" (effects (font (size 1.27 1.27))))
          (number "D4" (effects (font (size 1.27 1.27))))
        )
        (pin power_in line (at 63.5 -5.08 180) (length 3.81)
          (name "VCCAUX" (effects (font (size 1.27 1.27))))
          (number "D5" (effects (font (size 1.27 1.27))))
        )
        (pin power_in line (at 63.5 -101.6 180) (length 3.81)
          (name "GNDPLL_DPHY_X" (effects (font (size 1.27 1.27))))
          (number "D6" (effects (font (size 1.27 1.27))))
        )
        (pin bidirectional line (at 63.5 -45.72 180) (length 3.81)
          (name "VCCPLL_DPHY0" (effects (font (size 1.27 1.27))))
          (number "D7" (effects (font (size 1.27 1.27))))
        )
        (pin bidirectional line (at 0 -68.58 0) (length 3.81)
          (name "PB16A/PCLKT2_0" (effects (font (size 1.27 1.27))))
          (number "D9" (effects (font (size 1.27 1.27))))
        )
        (pin input line (at 0 -25.4 0) (length 3.81)
          (name "PB34A/GR_PCLK1_0" (effects (font (size 1.27 1.27))))
          (number "E1" (effects (font (size 1.27 1.27))))
        )
        (pin input line (at 0 -76.2 0) (length 3.81)
          (name "PB12B/GPLLC2_0" (effects (font (size 1.27 1.27))))
          (number "E10" (effects (font (size 1.27 1.27))))
        )
        (pin bidirectional line (at 0 -27.94 0) (length 3.81)
          (name "PB34B" (effects (font (size 1.27 1.27))))
          (number "E2" (effects (font (size 1.27 1.27))))
        )
        (pin power_in line (at 63.5 0 180) (length 3.81)
          (name "VCC" (effects (font (size 1.27 1.27))))
          (number "E4" (effects (font (size 1.27 1.27))))
        )
        (pin passive line (at 63.5 -106.68 180) (length 3.81) hide
          (name "GND" (effects (font (size 1.27 1.27))))
          (number "E5" (effects (font (size 1.27 1.27))))
        )
        (pin passive line (at 63.5 0 180) (length 3.81) hide
          (name "VCC" (effects (font (size 1.27 1.27))))
          (number "E6" (effects (font (size 1.27 1.27))))
        )
        (pin power_in line (at 63.5 -43.18 180) (length 3.81)
          (name "VCCA_DPHY0" (effects (font (size 1.27 1.27))))
          (number "E7" (effects (font (size 1.27 1.27))))
        )
        (pin input line (at 0 -73.66 0) (length 3.81)
          (name "PB12A/GPLLT2_0" (effects (font (size 1.27 1.27))))
          (number "E9" (effects (font (size 1.27 1.27))))
        )
        (pin bidirectional line (at 0 -30.48 0) (length 3.81)
          (name "PB38A" (effects (font (size 1.27 1.27))))
          (number "F1" (effects (font (size 1.27 1.27))))
        )
        (pin bidirectional line (at 0 -81.28 0) (length 3.81)
          (name "PB6B" (effects (font (size 1.27 1.27))))
          (number "F10" (effects (font (size 1.27 1.27))))
        )
        (pin bidirectional line (at 0 -33.02 0) (length 3.81)
          (name "PB38B" (effects (font (size 1.27 1.27))))
          (number "F2" (effects (font (size 1.27 1.27))))
        )
        (pin power_in line (at 0 -20.32 0) (length 3.81)
          (name "VCCIO0" (effects (font (size 1.27 1.27))))
          (number "F4" (effects (font (size 1.27 1.27))))
        )
        (pin power_in line (at 0 -60.96 0) (length 3.81)
          (name "VCCIO1" (effects (font (size 1.27 1.27))))
          (number "F5" (effects (font (size 1.27 1.27))))
        )
        (pin power_in line (at 0 -109.22 0) (length 3.81)
          (name "VCCIO2" (effects (font (size 1.27 1.27))))
          (number "F6" (effects (font (size 1.27 1.27))))
        )
        (pin passive line (at 0 -109.22 0) (length 3.81) hide
          (name "VCCIO2" (effects (font (size 1.27 1.27))))
          (number "F7" (effects (font (size 1.27 1.27))))
        )
        (pin input line (at 0 -78.74 0) (length 3.81)
          (name "PB6A/GR_PCLK2_0" (effects (font (size 1.27 1.27))))
          (number "F9" (effects (font (size 1.27 1.27))))
        )
        (pin bidirectional line (at 0 -10.16 0) (length 3.81)
          (name "PB50/MOSI" (effects (font (size 1.27 1.27))))
          (number "G1" (effects (font (size 1.27 1.27))))
        )
        (pin bidirectional line (at 0 -86.36 0) (length 3.81)
          (name "PB2B" (effects (font (size 1.27 1.27))))
          (number "G10" (effects (font (size 1.27 1.27))))
        )
        (pin passive line (at 63.5 -106.68 180) (length 3.81) hide
          (name "GND" (effects (font (size 1.27 1.27))))
          (number "G2" (effects (font (size 1.27 1.27))))
        )
        (pin passive line (at 0 -60.96 0) (length 3.81) hide
          (name "VCCIO1" (effects (font (size 1.27 1.27))))
          (number "G4" (effects (font (size 1.27 1.27))))
        )
        (pin passive line (at 63.5 -106.68 180) (length 3.81) hide
          (name "GND" (effects (font (size 1.27 1.27))))
          (number "G5" (effects (font (size 1.27 1.27))))
        )
        (pin power_in line (at 63.5 -10.16 180) (length 3.81)
          (name "VCCGPLL" (effects (font (size 1.27 1.27))))
          (number "G6" (effects (font (size 1.27 1.27))))
        )
        (pin power_in line (at 63.5 -104.14 180) (length 3.81)
          (name "GNDGPLL" (effects (font (size 1.27 1.27))))
          (number "G7" (effects (font (size 1.27 1.27))))
        )
        (pin bidirectional line (at 0 -83.82 0) (length 3.81)
          (name "PB2A" (effects (font (size 1.27 1.27))))
          (number "G9" (effects (font (size 1.27 1.27))))
        )
        (pin bidirectional line (at 0 -12.7 0) (length 3.81)
          (name "PB52/SPI_SS/CSN/SCL" (effects (font (size 1.27 1.27))))
          (number "H1" (effects (font (size 1.27 1.27))))
        )
        (pin bidirectional line (at 0 -91.44 0) (length 3.81)
          (name "PB2C/MIPI_CLKT2_0" (effects (font (size 1.27 1.27))))
          (number "H10" (effects (font (size 1.27 1.27))))
        )
        (pin input line (at 0 0 0) (length 3.81)
          (name "CRESET_B" (effects (font (size 1.27 1.27))))
          (number "H2" (effects (font (size 1.27 1.27))))
        )
        (pin bidirectional line (at 0 -88.9 0) (length 3.81)
          (name "PB2D/MIPI_CLKC2_0" (effects (font (size 1.27 1.27))))
          (number "H9" (effects (font (size 1.27 1.27))))
        )
        (pin bidirectional line (at 0 -15.24 0) (length 3.81)
          (name "PB53/SPI_SCK/MCK/SDA" (effects (font (size 1.27 1.27))))
          (number "J1" (effects (font (size 1.27 1.27))))
        )
        (pin bidirectional line (at 0 -99.06 0) (length 3.81)
          (name "PB6C" (effects (font (size 1.27 1.27))))
          (number "J10" (effects (font (size 1.27 1.27))))
        )
        (pin passive line (at 0 -2.54 0) (length 3.81)
          (name "PB49/PMU_WKUPN/CDONE" (effects (font (size 1.27 1.27))))
          (number "J2" (effects (font (size 1.27 1.27))))
        )
        (pin bidirectional line (at 0 -45.72 0) (length 3.81)
          (name "PB43D" (effects (font (size 1.27 1.27))))
          (number "J3" (effects (font (size 1.27 1.27))))
        )
        (pin bidirectional line (at 0 -43.18 0) (length 3.81)
          (name "PB38D" (effects (font (size 1.27 1.27))))
          (number "J4" (effects (font (size 1.27 1.27))))
        )
        (pin bidirectional line (at 0 -40.64 0) (length 3.81)
          (name "PB34D/MIPI_CLKC1_0" (effects (font (size 1.27 1.27))))
          (number "J5" (effects (font (size 1.27 1.27))))
        )
        (pin bidirectional line (at 0 -38.1 0) (length 3.81)
          (name "PB29D/PCLKC1_1" (effects (font (size 1.27 1.27))))
          (number "J6" (effects (font (size 1.27 1.27))))
        )
        (pin bidirectional line (at 0 -35.56 0) (length 3.81)
          (name "PB29A/PCLKT1_0" (effects (font (size 1.27 1.27))))
          (number "J7" (effects (font (size 1.27 1.27))))
        )
        (pin bidirectional line (at 0 -93.98 0) (length 3.81)
          (name "PB16D/PCLKC2_1" (effects (font (size 1.27 1.27))))
          (number "J8" (effects (font (size 1.27 1.27))))
        )
        (pin bidirectional line (at 0 -96.52 0) (length 3.81)
          (name "PB6D" (effects (font (size 1.27 1.27))))
          (number "J9" (effects (font (size 1.27 1.27))))
        )
        (pin bidirectional line (at 0 -17.78 0) (length 3.81)
          (name "PB51/MISO" (effects (font (size 1.27 1.27))))
          (number "K1" (effects (font (size 1.27 1.27))))
        )
        (pin bidirectional line (at 0 -106.68 0) (length 3.81)
          (name "PB12C" (effects (font (size 1.27 1.27))))
          (number "K10" (effects (font (size 1.27 1.27))))
        )
        (pin bidirectional line (at 0 -7.62 0) (length 3.81)
          (name "PB47/PCLKT0_0/USER_SDA" (effects (font (size 1.27 1.27))))
          (number "K2" (effects (font (size 1.27 1.27))))
        )
        (pin bidirectional line (at 0 -58.42 0) (length 3.81)
          (name "PB43C" (effects (font (size 1.27 1.27))))
          (number "K3" (effects (font (size 1.27 1.27))))
        )
        (pin bidirectional line (at 0 -55.88 0) (length 3.81)
          (name "PB38C" (effects (font (size 1.27 1.27))))
          (number "K4" (effects (font (size 1.27 1.27))))
        )
        (pin bidirectional line (at 0 -53.34 0) (length 3.81)
          (name "PB34C/MIPI_CLKT1_0" (effects (font (size 1.27 1.27))))
          (number "K5" (effects (font (size 1.27 1.27))))
        )
        (pin bidirectional line (at 0 -50.8 0) (length 3.81)
          (name "PB29C/PCLKT1_1" (effects (font (size 1.27 1.27))))
          (number "K6" (effects (font (size 1.27 1.27))))
        )
        (pin bidirectional line (at 0 -48.26 0) (length 3.81)
          (name "PB29B/PCLKC1_0" (effects (font (size 1.27 1.27))))
          (number "K7" (effects (font (size 1.27 1.27))))
        )
        (pin bidirectional line (at 0 -101.6 0) (length 3.81)
          (name "PB16C/PCLKT2_1" (effects (font (size 1.27 1.27))))
          (number "K8" (effects (font (size 1.27 1.27))))
        )
        (pin bidirectional line (at 0 -104.14 0) (length 3.81)
          (name "PB12D" (effects (font (size 1.27 1.27))))
          (number "K9" (effects (font (size 1.27 1.27))))
        )
      )
    )
	(symbol "sdi-mipi-bridge:FB_120Z_2A_0603" (pin_numbers hide) (pin_names hide) (in_bom yes) (on_board yes)
      (property "Reference" "FB" (at 15.24 -2.54 0)
        (effects (font (size 1.27 1.27) (thickness 0.15)) (justify left bottom))
      )
      (property "Value" "FB_120Z_2A_0603" (at 15.24 -5.08 0)
        (effects (font (size 1.27 1.27) (thickness 0.15)) (justify left bottom) hide)
      )
      (property "Footprint" "sdi-mipi-bridge-footprints:FB_0603_1608Metric" (at 15.24 -7.62 0)
        (effects (font (size 1.27 1.27) (thickness 0.15)) (justify left bottom) hide)
      )
      (property "Datasheet" "https://www.murata.com/en-us/products/productdata/8796738650142/ENFA0003.pdf" (at 15.24 -10.16 0)
        (effects (font (size 1.27 1.27) (thickness 0.15)) (justify left bottom) hide)
      )
      (property "MPN" "BLM18PG121SN1D" (at 15.24 -12.7 0)
        (effects (font (size 1.27 1.27) (thickness 0.15)) (justify left bottom))
      )
      (property "Manufacturer" "Murata" (at 15.24 -15.24 0)
        (effects (font (size 1.27 1.27) (thickness 0.15)) (justify left bottom) hide)
      )
      (property "Val" "240" (at 20.32 -10.16 0)
        (effects (font (size 1.27 1.27) (thickness 0.15)) (justify left bottom))
      )
      (property "Author" "Antmicro" (at 15.24 -17.78 0)
        (effects (font (size 1.27 1.27) (thickness 0.15)) (justify left bottom) hide)
      )
      (property "Current" "0.2A" (at 20.32 -22.86 0)
        (effects (font (size 1.27 1.27) (thickness 0.15)) (justify left bottom) hide)
      )
      (property "License" "Apache-2.0" (at 15.24 -20.32 0)
        (effects (font (size 1.27 1.27) (thickness 0.15)) (justify left bottom) hide)
      )
      (property "ki_keywords" " Multilayer Suppression Beads " (at 0 0 0)
        (effects (font (size 1.27 1.27)) hide)
      )
      (property "ki_description" "Ferrite Beads WE-TMSB Suppression 240Ohm 200mA " (at 0 0 0)
        (effects (font (size 1.27 1.27)) hide)
      )
      (symbol "FB_120Z_2A_0603_0_1"
        (polyline
          (pts
            (xy 1.651 0)
            (xy 1.2446 0)
          )
          (stroke (width 0) (type default))
          (fill (type none))
        )
        (polyline
          (pts
            (xy 3.81 0)
            (xy 3.3274 0)
          )
          (stroke (width 0) (type default))
          (fill (type none))
        )
        (polyline
          (pts
            (xy 2.2606 -1.8288)
            (xy 1.0414 -1.1176)
            (xy 2.7432 1.8288)
            (xy 3.9624 1.1176)
            (xy 2.2606 -1.8288)
          )
          (stroke (width 0) (type default))
          (fill (type none))
        )
      )
      (symbol "FB_120Z_2A_0603_1_1"
        (pin passive line (at 0 0 0) (length 1.27)
          (name "~" (effects (font (size 1.27 1.27))))
          (number "1" (effects (font (size 1.27 1.27))))
        )
        (pin passive line (at 5.08 0 180) (length 1.27)
          (name "~" (effects (font (size 1.27 1.27))))
          (number "2" (effects (font (size 1.27 1.27))))
        )
      )
    )
	(symbol "sdi-mipi-bridge:GNDA" (power) (pin_names (offset 0)) (in_bom yes) (on_board yes)
      (property "Reference" "#PWR" (at 0 -6.35 0)
        (effects (font (size 1.27 1.27)) hide)
      )
      (property "Value" "GNDA" (at 0 -3.81 0)
        (effects (font (size 1.27 1.27)))
      )
      (property "Footprint" "" (at 0 0 0)
        (effects (font (size 1.27 1.27)) hide)
      )
      (property "Datasheet" "" (at 0 0 0)
        (effects (font (size 1.27 1.27)) hide)
      )
      (symbol "GNDA_0_1"
        (polyline
          (pts
            (xy 0 0)
            (xy 0 -1.27)
            (xy 1.27 -1.27)
            (xy 0 -2.54)
            (xy -1.27 -1.27)
            (xy 0 -1.27)
          )
          (stroke (width 0) (type default))
          (fill (type none))
        )
      )
      (symbol "GNDA_1_1"
        (pin power_in line (at 0 0 270) (length 0) hide
          (name "GNDA" (effects (font (size 1.27 1.27))))
          (number "1" (effects (font (size 1.27 1.27))))
        )
      )
    )
	(symbol "sdi-mipi-bridge:GNDREF" (power) (pin_names (offset 0)) (in_bom yes) (on_board yes)
      (property "Reference" "#PWR" (at 0 -6.35 0)
        (effects (font (size 1.27 1.27)) hide)
      )
      (property "Value" "GNDREF" (at 0 -3.81 0)
        (effects (font (size 1.27 1.27)))
      )
      (property "Footprint" "" (at 0 0 0)
        (effects (font (size 1.27 1.27)) hide)
      )
      (property "Datasheet" "" (at 0 0 0)
        (effects (font (size 1.27 1.27)) hide)
      )
      (symbol "GNDREF_0_1"
        (polyline
          (pts
            (xy -0.635 -1.905)
            (xy 0.635 -1.905)
          )
          (stroke (width 0) (type default))
          (fill (type none))
        )
        (polyline
          (pts
            (xy -0.127 -2.54)
            (xy 0.127 -2.54)
          )
          (stroke (width 0) (type default))
          (fill (type none))
        )
        (polyline
          (pts
            (xy 0 -1.27)
            (xy 0 0)
          )
          (stroke (width 0) (type default))
          (fill (type none))
        )
        (polyline
          (pts
            (xy 1.27 -1.27)
            (xy -1.27 -1.27)
          )
          (stroke (width 0) (type default))
          (fill (type none))
        )
      )
      (symbol "GNDREF_1_1"
        (pin power_in line (at 0 0 270) (length 0) hide
          (name "GNDREF" (effects (font (size 1.27 1.27))))
          (number "1" (effects (font (size 1.27 1.27))))
        )
      )
    )
	(symbol "sdi-mipi-bridge:GS2971A" (in_bom yes) (on_board yes)
      (property "Reference" "U" (at 55.88 -2.54 0)
        (effects (font (size 1.27 1.27) (thickness 0.15)) (justify left bottom))
      )
      (property "Value" "GS2971A" (at 55.88 -5.08 0)
        (effects (font (size 1.27 1.27) (thickness 0.15)) (justify left bottom))
      )
      (property "Footprint" "sdi-mipi-bridge-footprints:BGA100_11x11mm_SEMTECH" (at 55.88 -7.62 0)
        (effects (font (size 1.27 1.27) (thickness 0.15)) (justify left bottom) hide)
      )
      (property "Datasheet" "https://semtech.my.salesforce.com/sfc/p/#E0000000JelG/a/44000000MD3i/kpmMkrmUWgHlbCOwdLzVohMm1SDPoVH85guEGK.KXTc" (at 55.88 -10.16 0)
        (effects (font (size 1.27 1.27) (thickness 0.15)) (justify left bottom) hide)
      )
      (property "MPN" "GS2971A" (at 55.88 -12.7 0)
        (effects (font (size 1.27 1.27) (thickness 0.15)) (justify left bottom) hide)
      )
      (property "Manufacturer" "Semtech" (at 55.88 -15.24 0)
        (effects (font (size 1.27 1.27) (thickness 0.15)) (justify left bottom) hide)
      )
      (property "Author" "Antmicro" (at 55.88 -17.78 0)
        (effects (font (size 1.27 1.27) (thickness 0.15)) (justify left bottom) hide)
      )
      (property "License" "Apache-2.0" (at 55.88 -20.32 0)
        (effects (font (size 1.27 1.27) (thickness 0.15)) (justify left bottom) hide)
      )
      (property "ki_locked" "" (at 0 0 0)
        (effects (font (size 1.27 1.27)))
      )
      (property "ki_description" "3Gb/s, HD, SD SDI Receiver, with Integrated Adaptive Cable Equalizer complete\nwith SMPTE Audio and Video Processing" (at 0 0 0)
        (effects (font (size 1.27 1.27)) hide)
      )
      (symbol "GS2971A_1_1"
        (rectangle (start 3.81 2.54) (end 22.86 -50.8)
          (stroke (width 0.254) (type default))
          (fill (type background))
        )
        (pin output line (at 26.67 -43.18 180) (length 3.81)
          (name "DOUT17" (effects (font (size 1.27 1.27))))
          (number "A10" (effects (font (size 1.27 1.27))))
        )
        (pin output line (at 0 -3.81 0) (length 3.81)
          (name "STAT0" (effects (font (size 1.27 1.27))))
          (number "A5" (effects (font (size 1.27 1.27))))
        )
        (pin output line (at 0 -6.35 0) (length 3.81)
          (name "STAT1" (effects (font (size 1.27 1.27))))
          (number "A6" (effects (font (size 1.27 1.27))))
        )
        (pin output line (at 0 0 0) (length 3.81)
          (name "PCLK" (effects (font (size 1.27 1.27))))
          (number "A8" (effects (font (size 1.27 1.27))))
        )
        (pin output line (at 26.67 -45.72 180) (length 3.81)
          (name "DOUT18" (effects (font (size 1.27 1.27))))
          (number "A9" (effects (font (size 1.27 1.27))))
        )
        (pin output line (at 26.67 -38.1 180) (length 3.81)
          (name "DOUT15" (effects (font (size 1.27 1.27))))
          (number "B10" (effects (font (size 1.27 1.27))))
        )
        (pin output line (at 0 -8.89 0) (length 3.81)
          (name "STAT2" (effects (font (size 1.27 1.27))))
          (number "B5" (effects (font (size 1.27 1.27))))
        )
        (pin output line (at 0 -11.43 0) (length 3.81)
          (name "STAT3" (effects (font (size 1.27 1.27))))
          (number "B6" (effects (font (size 1.27 1.27))))
        )
        (pin output line (at 26.67 -48.26 180) (length 3.81)
          (name "DOUT19" (effects (font (size 1.27 1.27))))
          (number "B8" (effects (font (size 1.27 1.27))))
        )
        (pin output line (at 26.67 -40.64 180) (length 3.81)
          (name "DOUT16" (effects (font (size 1.27 1.27))))
          (number "B9" (effects (font (size 1.27 1.27))))
        )
        (pin output line (at 26.67 -33.02 180) (length 3.81)
          (name "DOUT13" (effects (font (size 1.27 1.27))))
          (number "C10" (effects (font (size 1.27 1.27))))
        )
        (pin output line (at 0 -13.97 0) (length 3.81)
          (name "STAT4" (effects (font (size 1.27 1.27))))
          (number "C5" (effects (font (size 1.27 1.27))))
        )
        (pin output line (at 0 -16.51 0) (length 3.81)
          (name "STAT5" (effects (font (size 1.27 1.27))))
          (number "C6" (effects (font (size 1.27 1.27))))
        )
        (pin output line (at 26.67 -30.48 180) (length 3.81)
          (name "DOUT12" (effects (font (size 1.27 1.27))))
          (number "C8" (effects (font (size 1.27 1.27))))
        )
        (pin output line (at 26.67 -35.56 180) (length 3.81)
          (name "DOUT14" (effects (font (size 1.27 1.27))))
          (number "C9" (effects (font (size 1.27 1.27))))
        )
        (pin output line (at 26.67 -27.94 180) (length 3.81)
          (name "DOUT11" (effects (font (size 1.27 1.27))))
          (number "E10" (effects (font (size 1.27 1.27))))
        )
        (pin output line (at 26.67 -25.4 180) (length 3.81)
          (name "DOUT10" (effects (font (size 1.27 1.27))))
          (number "E9" (effects (font (size 1.27 1.27))))
        )
        (pin output line (at 26.67 -22.86 180) (length 3.81)
          (name "DOUT09" (effects (font (size 1.27 1.27))))
          (number "F10" (effects (font (size 1.27 1.27))))
        )
        (pin output line (at 26.67 -20.32 180) (length 3.81)
          (name "DOUT08" (effects (font (size 1.27 1.27))))
          (number "F9" (effects (font (size 1.27 1.27))))
        )
        (pin output line (at 26.67 -17.78 180) (length 3.81)
          (name "DOUT07" (effects (font (size 1.27 1.27))))
          (number "H10" (effects (font (size 1.27 1.27))))
        )
        (pin output line (at 0 -20.32 0) (length 3.81)
          (name "WCLK" (effects (font (size 1.27 1.27))))
          (number "H4" (effects (font (size 1.27 1.27))))
        )
        (pin output line (at 26.67 -15.24 180) (length 3.81)
          (name "DOUT06" (effects (font (size 1.27 1.27))))
          (number "H9" (effects (font (size 1.27 1.27))))
        )
        (pin output line (at 0 -43.18 0) (length 3.81)
          (name "SDO+" (effects (font (size 1.27 1.27))))
          (number "J1" (effects (font (size 1.27 1.27))))
        )
        (pin output line (at 26.67 -12.7 180) (length 3.81)
          (name "DOUT05" (effects (font (size 1.27 1.27))))
          (number "J10" (effects (font (size 1.27 1.27))))
        )
        (pin output line (at 0 -30.48 0) (length 3.81)
          (name "AOUT_{1/2}" (effects (font (size 1.27 1.27))))
          (number "J3" (effects (font (size 1.27 1.27))))
        )
        (pin output line (at 0 -22.86 0) (length 3.81)
          (name "ACLK" (effects (font (size 1.27 1.27))))
          (number "J4" (effects (font (size 1.27 1.27))))
        )
        (pin output line (at 0 -35.56 0) (length 3.81)
          (name "AOUT_{5/6}" (effects (font (size 1.27 1.27))))
          (number "J5" (effects (font (size 1.27 1.27))))
        )
        (pin output line (at 26.67 -2.54 180) (length 3.81)
          (name "DOUT01" (effects (font (size 1.27 1.27))))
          (number "J8" (effects (font (size 1.27 1.27))))
        )
        (pin output line (at 26.67 -10.16 180) (length 3.81)
          (name "DOUT04" (effects (font (size 1.27 1.27))))
          (number "J9" (effects (font (size 1.27 1.27))))
        )
        (pin output line (at 0 -45.72 0) (length 3.81)
          (name "SDO-" (effects (font (size 1.27 1.27))))
          (number "K1" (effects (font (size 1.27 1.27))))
        )
        (pin output line (at 26.67 -7.62 180) (length 3.81)
          (name "DOUT03" (effects (font (size 1.27 1.27))))
          (number "K10" (effects (font (size 1.27 1.27))))
        )
        (pin output line (at 0 -33.02 0) (length 3.81)
          (name "AOUT_{3/4}" (effects (font (size 1.27 1.27))))
          (number "K3" (effects (font (size 1.27 1.27))))
        )
        (pin output line (at 0 -25.4 0) (length 3.81)
          (name "AMCLK" (effects (font (size 1.27 1.27))))
          (number "K4" (effects (font (size 1.27 1.27))))
        )
        (pin output line (at 0 -38.1 0) (length 3.81)
          (name "AOUT_{7/8}" (effects (font (size 1.27 1.27))))
          (number "K5" (effects (font (size 1.27 1.27))))
        )
        (pin output line (at 26.67 0 180) (length 3.81)
          (name "DOUT0" (effects (font (size 1.27 1.27))))
          (number "K8" (effects (font (size 1.27 1.27))))
        )
        (pin output line (at 26.67 -5.08 180) (length 3.81)
          (name "DOUT02" (effects (font (size 1.27 1.27))))
          (number "K9" (effects (font (size 1.27 1.27))))
        )
      )
      (symbol "GS2971A_2_1"
        (rectangle (start 3.81 2.54) (end 27.94 -40.64)
          (stroke (width 0.254) (type default))
          (fill (type background))
        )
        (pin input line (at 0 -5.08 0) (length 3.81)
          (name "VBG" (effects (font (size 1.27 1.27))))
          (number "A1" (effects (font (size 1.27 1.27))))
        )
        (pin input line (at 0 -2.54 0) (length 3.81)
          (name "LF" (effects (font (size 1.27 1.27))))
          (number "A2" (effects (font (size 1.27 1.27))))
        )
        (pin input line (at 0 0 0) (length 3.81)
          (name "LB_CONT" (effects (font (size 1.27 1.27))))
          (number "A3" (effects (font (size 1.27 1.27))))
        )
        (pin no_connect line (at 3.81 -17.78 0) (length 3.81) hide
          (name "RSV" (effects (font (size 1.27 1.27))))
          (number "B3" (effects (font (size 1.27 1.27))))
        )
        (pin input line (at 0 -31.75 0) (length 3.81)
          (name "SDI+" (effects (font (size 1.27 1.27))))
          (number "C1" (effects (font (size 1.27 1.27))))
        )
        (pin input line (at 31.75 -20.32 180) (length 3.81)
          (name "RESET_TRST" (effects (font (size 1.27 1.27))))
          (number "C7" (effects (font (size 1.27 1.27))))
        )
        (pin input line (at 0 -34.29 0) (length 3.81)
          (name "SDI-" (effects (font (size 1.27 1.27))))
          (number "D1" (effects (font (size 1.27 1.27))))
        )
        (pin input line (at 31.75 -33.02 180) (length 3.81)
          (name "SW_EN" (effects (font (size 1.27 1.27))))
          (number "D7" (effects (font (size 1.27 1.27))))
        )
        (pin input line (at 31.75 -15.24 180) (length 3.81)
          (name "JTAG/~{HOST}" (effects (font (size 1.27 1.27))))
          (number "D8" (effects (font (size 1.27 1.27))))
        )
        (pin output line (at 31.75 -38.1 180) (length 3.81)
          (name "SDOUT_TDO" (effects (font (size 1.27 1.27))))
          (number "E7" (effects (font (size 1.27 1.27))))
        )
        (pin input line (at 31.75 -25.4 180) (length 3.81)
          (name "SDIN_TDI" (effects (font (size 1.27 1.27))))
          (number "E8" (effects (font (size 1.27 1.27))))
        )
        (pin passive line (at 0 -22.86 0) (length 3.81)
          (name "AGC+" (effects (font (size 1.27 1.27))))
          (number "F1" (effects (font (size 1.27 1.27))))
        )
        (pin no_connect line (at 3.81 -17.78 0) (length 3.81) hide
          (name "RSV" (effects (font (size 1.27 1.27))))
          (number "F2" (effects (font (size 1.27 1.27))))
        )
        (pin input line (at 31.75 -10.16 180) (length 3.81)
          (name "~{CS}_TMS" (effects (font (size 1.27 1.27))))
          (number "F7" (effects (font (size 1.27 1.27))))
        )
        (pin input line (at 31.75 -22.86 180) (length 3.81)
          (name "SCLK_TCK" (effects (font (size 1.27 1.27))))
          (number "F8" (effects (font (size 1.27 1.27))))
        )
        (pin passive line (at 0 -25.4 0) (length 3.81)
          (name "AGC-" (effects (font (size 1.27 1.27))))
          (number "G1" (effects (font (size 1.27 1.27))))
        )
        (pin input line (at 31.75 -17.78 180) (length 3.81)
          (name "~{RC_BYP}" (effects (font (size 1.27 1.27))))
          (number "G3" (effects (font (size 1.27 1.27))))
        )
        (pin bidirectional line (at 31.75 -2.54 180) (length 3.81)
          (name "~{SMPTE_BYPASS}" (effects (font (size 1.27 1.27))))
          (number "G7" (effects (font (size 1.27 1.27))))
        )
        (pin bidirectional line (at 31.75 0 180) (length 3.81)
          (name "DVB_ASI" (effects (font (size 1.27 1.27))))
          (number "G8" (effects (font (size 1.27 1.27))))
        )
        (pin input line (at 31.75 -7.62 180) (length 3.81)
          (name "AUDIO_EN/~{DIS}" (effects (font (size 1.27 1.27))))
          (number "H3" (effects (font (size 1.27 1.27))))
        )
        (pin input line (at 31.75 -35.56 180) (length 3.81)
          (name "TIM_861" (effects (font (size 1.27 1.27))))
          (number "H5" (effects (font (size 1.27 1.27))))
        )
        (pin output line (at 0 -15.24 0) (length 3.81)
          (name "XTAL_OUT" (effects (font (size 1.27 1.27))))
          (number "H6" (effects (font (size 1.27 1.27))))
        )
        (pin input line (at 31.75 -5.08 180) (length 3.81)
          (name "20BIT/~{10BIT}" (effects (font (size 1.27 1.27))))
          (number "H7" (effects (font (size 1.27 1.27))))
        )
        (pin input line (at 31.75 -12.7 180) (length 3.81)
          (name "IOPROC_EN/~{DIS}" (effects (font (size 1.27 1.27))))
          (number "H8" (effects (font (size 1.27 1.27))))
        )
        (pin input line (at 31.75 -27.94 180) (length 3.81)
          (name "SDO_EN/DIS" (effects (font (size 1.27 1.27))))
          (number "J2" (effects (font (size 1.27 1.27))))
        )
        (pin input line (at 0 -12.7 0) (length 3.81)
          (name "XTAL2" (effects (font (size 1.27 1.27))))
          (number "J6" (effects (font (size 1.27 1.27))))
        )
        (pin input line (at 31.75 -30.48 180) (length 3.81)
          (name "STANDBY" (effects (font (size 1.27 1.27))))
          (number "K2" (effects (font (size 1.27 1.27))))
        )
        (pin input line (at 0 -10.16 0) (length 3.81)
          (name "XTAL1" (effects (font (size 1.27 1.27))))
          (number "K6" (effects (font (size 1.27 1.27))))
        )
      )
      (symbol "GS2971A_3_1"
        (rectangle (start 3.81 2.54) (end 22.86 -17.78)
          (stroke (width 0.254) (type default))
          (fill (type background))
        )
        (pin power_in line (at 0 0 0) (length 3.81)
          (name "VCO_{VDD}" (effects (font (size 1.27 1.27))))
          (number "A4" (effects (font (size 1.27 1.27))))
        )
        (pin power_in line (at 0 -15.24 0) (length 3.81)
          (name "IO_{VDD}" (effects (font (size 1.27 1.27))))
          (number "A7" (effects (font (size 1.27 1.27))))
        )
        (pin power_in line (at 0 -5.08 0) (length 3.81)
          (name "A_{VDD}" (effects (font (size 1.27 1.27))))
          (number "B1" (effects (font (size 1.27 1.27))))
        )
        (pin power_in line (at 0 -2.54 0) (length 3.81)
          (name "PLL_{VDD}" (effects (font (size 1.27 1.27))))
          (number "B2" (effects (font (size 1.27 1.27))))
        )
        (pin power_in line (at 26.67 0 180) (length 3.81)
          (name "VCO_{GND}" (effects (font (size 1.27 1.27))))
          (number "B4" (effects (font (size 1.27 1.27))))
        )
        (pin power_in line (at 26.67 -15.24 180) (length 3.81)
          (name "IO_{GND}" (effects (font (size 1.27 1.27))))
          (number "B7" (effects (font (size 1.27 1.27))))
        )
        (pin power_in line (at 26.67 -5.08 180) (length 3.81)
          (name "A_{GND}" (effects (font (size 1.27 1.27))))
          (number "C2" (effects (font (size 1.27 1.27))))
        )
        (pin passive line (at 0 -2.54 0) (length 3.81) hide
          (name "PLL_{VDD}" (effects (font (size 1.27 1.27))))
          (number "C3" (effects (font (size 1.27 1.27))))
        )
        (pin passive line (at 0 -2.54 0) (length 3.81) hide
          (name "PLL_{VDD}" (effects (font (size 1.27 1.27))))
          (number "C4" (effects (font (size 1.27 1.27))))
        )
        (pin passive line (at 0 -15.24 0) (length 3.81) hide
          (name "IO_{VDD}" (effects (font (size 1.27 1.27))))
          (number "D10" (effects (font (size 1.27 1.27))))
        )
        (pin passive line (at 26.67 -5.08 180) (length 3.81) hide
          (name "A_{GND}" (effects (font (size 1.27 1.27))))
          (number "D2" (effects (font (size 1.27 1.27))))
        )
        (pin passive line (at 26.67 -5.08 180) (length 3.81) hide
          (name "A_{GND}" (effects (font (size 1.27 1.27))))
          (number "D3" (effects (font (size 1.27 1.27))))
        )
        (pin power_in line (at 26.67 -2.54 180) (length 3.81)
          (name "PLL_{GND}" (effects (font (size 1.27 1.27))))
          (number "D4" (effects (font (size 1.27 1.27))))
        )
        (pin power_in line (at 26.67 -12.7 180) (length 3.81)
          (name "CORE_{GND}" (effects (font (size 1.27 1.27))))
          (number "D5" (effects (font (size 1.27 1.27))))
        )
        (pin power_in line (at 0 -12.7 0) (length 3.81)
          (name "CORE_{VDD}" (effects (font (size 1.27 1.27))))
          (number "D6" (effects (font (size 1.27 1.27))))
        )
        (pin passive line (at 26.67 -15.24 180) (length 3.81) hide
          (name "IO_{GND}" (effects (font (size 1.27 1.27))))
          (number "D9" (effects (font (size 1.27 1.27))))
        )
        (pin power_in line (at 0 -7.62 0) (length 3.81)
          (name "EQ_{VDD}" (effects (font (size 1.27 1.27))))
          (number "E1" (effects (font (size 1.27 1.27))))
        )
        (pin power_in line (at 26.67 -7.62 180) (length 3.81)
          (name "EQ_{GND}" (effects (font (size 1.27 1.27))))
          (number "E2" (effects (font (size 1.27 1.27))))
        )
        (pin passive line (at 26.67 -5.08 180) (length 3.81) hide
          (name "A_{GND}" (effects (font (size 1.27 1.27))))
          (number "E3" (effects (font (size 1.27 1.27))))
        )
        (pin passive line (at 26.67 -2.54 180) (length 3.81) hide
          (name "PLL_{GND}" (effects (font (size 1.27 1.27))))
          (number "E4" (effects (font (size 1.27 1.27))))
        )
        (pin passive line (at 26.67 -12.7 180) (length 3.81) hide
          (name "CORE_{GND}" (effects (font (size 1.27 1.27))))
          (number "E5" (effects (font (size 1.27 1.27))))
        )
        (pin passive line (at 0 -12.7 0) (length 3.81) hide
          (name "CORE_{VDD}" (effects (font (size 1.27 1.27))))
          (number "E6" (effects (font (size 1.27 1.27))))
        )
        (pin passive line (at 26.67 -5.08 180) (length 3.81) hide
          (name "A_{GND}" (effects (font (size 1.27 1.27))))
          (number "F3" (effects (font (size 1.27 1.27))))
        )
        (pin passive line (at 26.67 -2.54 180) (length 3.81) hide
          (name "PLL_{GND}" (effects (font (size 1.27 1.27))))
          (number "F4" (effects (font (size 1.27 1.27))))
        )
        (pin passive line (at 26.67 -12.7 180) (length 3.81) hide
          (name "CORE_{GND}" (effects (font (size 1.27 1.27))))
          (number "F5" (effects (font (size 1.27 1.27))))
        )
        (pin passive line (at 0 -12.7 0) (length 3.81) hide
          (name "CORE_{VDD}" (effects (font (size 1.27 1.27))))
          (number "F6" (effects (font (size 1.27 1.27))))
        )
        (pin passive line (at 0 -15.24 0) (length 3.81) hide
          (name "IO_{VDD}" (effects (font (size 1.27 1.27))))
          (number "G10" (effects (font (size 1.27 1.27))))
        )
        (pin passive line (at 26.67 -5.08 180) (length 3.81) hide
          (name "A_{GND}" (effects (font (size 1.27 1.27))))
          (number "G2" (effects (font (size 1.27 1.27))))
        )
        (pin passive line (at 26.67 -12.7 180) (length 3.81) hide
          (name "CORE_{GND}" (effects (font (size 1.27 1.27))))
          (number "G4" (effects (font (size 1.27 1.27))))
        )
        (pin passive line (at 26.67 -12.7 180) (length 3.81) hide
          (name "CORE_{GND}" (effects (font (size 1.27 1.27))))
          (number "G5" (effects (font (size 1.27 1.27))))
        )
        (pin passive line (at 0 -12.7 0) (length 3.81) hide
          (name "CORE_{VDD}" (effects (font (size 1.27 1.27))))
          (number "G6" (effects (font (size 1.27 1.27))))
        )
        (pin passive line (at 26.67 -15.24 180) (length 3.81) hide
          (name "IO_{GND}" (effects (font (size 1.27 1.27))))
          (number "G9" (effects (font (size 1.27 1.27))))
        )
        (pin power_in line (at 0 -10.16 0) (length 3.81)
          (name "BUFF_{VDD}" (effects (font (size 1.27 1.27))))
          (number "H1" (effects (font (size 1.27 1.27))))
        )
        (pin power_in line (at 26.67 -10.16 180) (length 3.81)
          (name "BUFF_{GND}" (effects (font (size 1.27 1.27))))
          (number "H2" (effects (font (size 1.27 1.27))))
        )
        (pin passive line (at 26.67 -15.24 180) (length 3.81) hide
          (name "IO_{GND}" (effects (font (size 1.27 1.27))))
          (number "J7" (effects (font (size 1.27 1.27))))
        )
        (pin passive line (at 0 -15.24 0) (length 3.81) hide
          (name "IO_{VDD}" (effects (font (size 1.27 1.27))))
          (number "K7" (effects (font (size 1.27 1.27))))
        )
      )
    )
	(symbol "sdi-mipi-bridge:GS2988" (in_bom yes) (on_board yes)
      (property "Reference" "U" (at 55.88 -5.08 0)
        (effects (font (size 1.27 1.27) (thickness 0.15)) (justify left bottom))
      )
      (property "Value" "GS2988" (at 55.88 -7.62 0)
        (effects (font (size 1.27 1.27) (thickness 0.15)) (justify left bottom))
      )
      (property "Footprint" "sdi-mipi-bridge-footprints:QFN-16_1EP_4x4mm_P0.65mm" (at 55.88 -10.16 0)
        (effects (font (size 1.27 1.27) (thickness 0.15)) (justify left bottom) hide)
      )
      (property "Datasheet" "https://semtech.my.salesforce.com/sfc/p/#E0000000JelG/a/44000000MDIY/URmNPYk6YrvngFjCh2n.ZRVsjLb90QOH1YLezdH9vhM" (at 55.88 -12.7 0)
        (effects (font (size 1.27 1.27) (thickness 0.15)) (justify left bottom) hide)
      )
      (property "Manufacturer" "Semtech" (at 55.88 -15.24 0)
        (effects (font (size 1.27 1.27) (thickness 0.15)) (justify left bottom) hide)
      )
      (property "MPN" "GS2988-INE3" (at 55.88 -17.78 0)
        (effects (font (size 1.27 1.27) (thickness 0.15)) (justify left bottom) hide)
      )
      (property "Author" "Antmicro" (at 55.88 -20.32 0)
        (effects (font (size 1.27 1.27) (thickness 0.15)) (justify left bottom) hide)
      )
      (property "License" "Apache-2.0" (at 55.88 -22.86 0)
        (effects (font (size 1.27 1.27) (thickness 0.15)) (justify left bottom) hide)
      )
      (property "ki_keywords" "LVPECL/CML Cable driver 3Gb/s" (at 0 0 0)
        (effects (font (size 1.27 1.27)) hide)
      )
      (property "ki_description" "LVPECL/CML Cable driver 3Gb/s" (at 0 0 0)
        (effects (font (size 1.27 1.27)) hide)
      )
      (symbol "GS2988_0_1"
        (polyline
          (pts
            (xy 8.128 -3.81)
            (xy 8.89 -3.81)
          )
          (stroke (width 0.254) (type default))
          (fill (type none))
        )
        (polyline
          (pts
            (xy 11.43 -3.81)
            (xy 13.97 -3.81)
          )
          (stroke (width 0.254) (type default))
          (fill (type none))
        )
        (polyline
          (pts
            (xy 12.446 -6.35)
            (xy 13.97 -6.35)
          )
          (stroke (width 0.254) (type default))
          (fill (type none))
        )
        (rectangle (start 2.54 2.54) (end 20.32 -24.13)
          (stroke (width 0.254) (type default))
          (fill (type background))
        )
        (circle (center 8.382 -6.35) (radius 0.284)
          (stroke (width 0.254) (type default))
          (fill (type none))
        )
        (circle (center 12.065 -6.35) (radius 0.284)
          (stroke (width 0.254) (type default))
          (fill (type none))
        )
      )
      (symbol "GS2988_1_1"
        (polyline
          (pts
            (xy 8.89 -2.54)
            (xy 13.97 -5.08)
            (xy 8.89 -7.62)
            (xy 8.89 -2.54)
          )
          (stroke (width 0.254) (type default))
          (fill (type background))
        )
        (pin input line (at 0 -3.81 0) (length 2.54)
          (name "DDI+" (effects (font (size 1.27 1.27))))
          (number "1" (effects (font (size 1.27 1.27))))
        )
        (pin input line (at 0 -12.7 0) (length 2.54)
          (name "SD/~{HD}" (effects (font (size 1.27 1.27))))
          (number "10" (effects (font (size 1.27 1.27))))
        )
        (pin output line (at 22.86 -6.35 180) (length 2.54)
          (name "SDO-" (effects (font (size 1.27 1.27))))
          (number "11" (effects (font (size 1.27 1.27))))
        )
        (pin output line (at 22.86 -3.81 180) (length 2.54)
          (name "SDO+" (effects (font (size 1.27 1.27))))
          (number "12" (effects (font (size 1.27 1.27))))
        )
        (pin no_connect line (at 20.32 -20.32 180) (length 2.54) hide
          (name "NC" (effects (font (size 1.27 1.27))))
          (number "13" (effects (font (size 1.27 1.27))))
        )
        (pin output line (at 22.86 -12.7 180) (length 2.54)
          (name "~{OSP}" (effects (font (size 1.27 1.27))))
          (number "14" (effects (font (size 1.27 1.27))))
        )
        (pin no_connect line (at 20.32 -22.86 180) (length 2.54) hide
          (name "NC" (effects (font (size 1.27 1.27))))
          (number "15" (effects (font (size 1.27 1.27))))
        )
        (pin input line (at 0 -15.24 0) (length 2.54)
          (name "~{EQ_EN}" (effects (font (size 1.27 1.27))))
          (number "16" (effects (font (size 1.27 1.27))))
        )
        (pin passive line (at 0 -21.59 0) (length 2.54)
          (name "EP" (effects (font (size 1.27 1.27))))
          (number "17" (effects (font (size 1.27 1.27))))
        )
        (pin input line (at 0 -6.35 0) (length 2.54)
          (name "DDI-" (effects (font (size 1.27 1.27))))
          (number "2" (effects (font (size 1.27 1.27))))
        )
        (pin power_in line (at 0 -19.05 0) (length 2.54)
          (name "V_{EE}" (effects (font (size 1.27 1.27))))
          (number "3" (effects (font (size 1.27 1.27))))
        )
        (pin passive line (at 22.86 -15.24 180) (length 2.54)
          (name "RSET" (effects (font (size 1.27 1.27))))
          (number "4" (effects (font (size 1.27 1.27))))
        )
        (pin no_connect line (at 20.32 0 180) (length 2.54) hide
          (name "NC" (effects (font (size 1.27 1.27))))
          (number "5" (effects (font (size 1.27 1.27))))
        )
        (pin input line (at 0 -10.16 0) (length 2.54)
          (name "~{DISABLE}" (effects (font (size 1.27 1.27))))
          (number "6" (effects (font (size 1.27 1.27))))
        )
        (pin no_connect line (at 20.32 -8.89 180) (length 2.54) hide
          (name "NC" (effects (font (size 1.27 1.27))))
          (number "7" (effects (font (size 1.27 1.27))))
        )
        (pin no_connect line (at 20.32 -17.78 180) (length 2.54) hide
          (name "NC" (effects (font (size 1.27 1.27))))
          (number "8" (effects (font (size 1.27 1.27))))
        )
        (pin power_in line (at 0 0 0) (length 2.54)
          (name "V_{CC}" (effects (font (size 1.27 1.27))))
          (number "9" (effects (font (size 1.27 1.27))))
        )
      )
    )
	(symbol "sdi-mipi-bridge:LED_G_0603_LG_L29K-G2J1-24-Z" (pin_numbers hide) (pin_names hide) (in_bom yes) (on_board yes)
      (property "Reference" "D" (at 22.86 -5.08 0)
        (effects (font (size 1.27 1.27) (thickness 0.15)) (justify left bottom))
      )
      (property "Value" "LED_G_0603_LG_L29K-G2J1-24-Z" (at 22.86 -7.62 0)
        (effects (font (size 1.27 1.27) (thickness 0.15)) (justify left bottom))
      )
      (property "Footprint" "sdi-mipi-bridge-footprints:LED_0603_1608Metric_G" (at 22.86 -10.16 0)
        (effects (font (size 1.27 1.27) (thickness 0.15)) (justify left bottom) hide)
      )
      (property "Datasheet" "https://dammedia.osram.info/media/resource/hires/osram-dam-2493945/LG%20L29K.pdf" (at 22.86 -12.7 0)
        (effects (font (size 1.27 1.27) (thickness 0.15)) (justify left bottom) hide)
      )
      (property "MPN" "LG L29K-G2J1-24-Z" (at 22.86 -15.24 0)
        (effects (font (size 1.27 1.27) (thickness 0.15)) (justify left bottom) hide)
      )
      (property "Manufacturer" "Osram" (at 22.86 -17.78 0)
        (effects (font (size 1.27 1.27) (thickness 0.15)) (justify left bottom) hide)
      )
      (property "Author" "Antmicro" (at 22.86 -20.32 0)
        (effects (font (size 1.27 1.27) (thickness 0.15)) (justify left bottom) hide)
      )
      (property "License" "Apache-2.0" (at 22.86 -22.86 0)
        (effects (font (size 1.27 1.27) (thickness 0.15)) (justify left bottom) hide)
      )
      (symbol "LED_G_0603_LG_L29K-G2J1-24-Z_1_1"
        (polyline
          (pts
            (xy 5.08 1.27)
            (xy 5.08 -1.27)
          )
          (stroke (width 0.254) (type default))
          (fill (type none))
        )
        (polyline
          (pts
            (xy 2.54 1.27)
            (xy 2.54 -1.27)
            (xy 5.08 0)
            (xy 2.54 1.27)
          )
          (stroke (width 0.254) (type default))
          (fill (type outline))
        )
        (polyline
          (pts
            (xy 3.683 2.286)
            (xy 3.683 1.778)
            (xy 3.683 2.286)
            (xy 3.175 2.286)
            (xy 3.683 2.286)
            (xy 2.794 1.397)
          )
          (stroke (width 0.254) (type default))
          (fill (type none))
        )
        (polyline
          (pts
            (xy 4.699 2.032)
            (xy 4.699 1.524)
            (xy 4.699 2.032)
            (xy 4.191 2.032)
            (xy 4.699 2.032)
            (xy 3.683 1.016)
          )
          (stroke (width 0.254) (type default))
          (fill (type none))
        )
        (pin passive line (at 0 0 0) (length 2.54)
          (name "~" (effects (font (size 1.27 1.27))))
          (number "1" (effects (font (size 1.27 1.27))))
        )
        (pin passive line (at 7.62 0 180) (length 2.54)
          (name "2" (effects (font (size 1.27 1.27))))
          (number "2" (effects (font (size 1.27 1.27))))
        )
      )
    )
	(symbol "sdi-mipi-bridge:MAX8902B" (in_bom yes) (on_board yes)
      (property "Reference" "U" (at 27.94 -5.08 0)
        (effects (font (size 1.27 1.27) (thickness 0.15)) (justify left bottom))
      )
      (property "Value" "MAX8902B" (at 27.94 -10.16 0)
        (effects (font (size 1.27 1.27) (thickness 0.15)) (justify left bottom) hide)
      )
      (property "Footprint" "sdi-mipi-bridge-footprints:TDFN-8-1EP_2x2mm_P0.5mm" (at 27.94 -12.7 0)
        (effects (font (size 1.27 1.27) (thickness 0.15)) (justify left bottom) hide)
      )
      (property "Datasheet" "https://www.analog.com/media/en/technical-documentation/data-sheets/MAX8902-MAX8902B.pdf" (at 27.94 -15.24 0)
        (effects (font (size 1.27 1.27) (thickness 0.15)) (justify left bottom) hide)
      )
      (property "MPN" "MAX8902B" (at 27.94 -7.62 0)
        (effects (font (size 1.27 1.27) (thickness 0.15)) (justify left bottom))
      )
      (property "Manufacturer" "Maxim Integrated Products" (at 27.94 -17.78 0)
        (effects (font (size 1.27 1.27) (thickness 0.15)) (justify left bottom) hide)
      )
      (property "Author" "Antmicro" (at 27.94 -20.32 0)
        (effects (font (size 1.27 1.27) (thickness 0.15)) (justify left bottom) hide)
      )
      (property "License" "Apache-2.0" (at 27.94 -22.86 0)
        (effects (font (size 1.27 1.27) (thickness 0.15)) (justify left bottom) hide)
      )
      (property "ki_keywords" "IC" (at 0 0 0)
        (effects (font (size 1.27 1.27)) hide)
      )
      (property "ki_description" "LDO Voltage Regulator, Adjustable, 1.7V to 5.5V input, 150 mV drop., 0.6-5.3V/0.5A out, TDFN-8" (at 0 0 0)
        (effects (font (size 1.27 1.27)) hide)
      )
      (symbol "MAX8902B_1_1"
        (rectangle (start 2.54 1.27) (end 12.7 -19.05)
          (stroke (width 0.254) (type default))
          (fill (type background))
        )
        (pin input line (at 0 0 0) (length 2.54)
          (name "IN" (effects (font (size 1.27 1.27))))
          (number "1" (effects (font (size 1.27 1.27))))
        )
        (pin power_in line (at 15.24 -17.78 180) (length 2.54)
          (name "GND" (effects (font (size 1.27 1.27))))
          (number "2" (effects (font (size 1.27 1.27))))
        )
        (pin input line (at 0 -5.08 0) (length 2.54)
          (name "EN" (effects (font (size 1.27 1.27))))
          (number "3" (effects (font (size 1.27 1.27))))
        )
        (pin input line (at 15.24 -12.7 180) (length 2.54)
          (name "GS" (effects (font (size 1.27 1.27))))
          (number "4" (effects (font (size 1.27 1.27))))
        )
        (pin output line (at 0 -12.7 0) (length 2.54)
          (name "~{POK}" (effects (font (size 1.27 1.27))))
          (number "5" (effects (font (size 1.27 1.27))))
        )
        (pin input line (at 15.24 -8.89 180) (length 2.54)
          (name "FB" (effects (font (size 1.27 1.27))))
          (number "6" (effects (font (size 1.27 1.27))))
        )
        (pin input line (at 15.24 -5.08 180) (length 2.54)
          (name "BYP" (effects (font (size 1.27 1.27))))
          (number "7" (effects (font (size 1.27 1.27))))
        )
        (pin output line (at 15.24 0 180) (length 2.54)
          (name "OUT" (effects (font (size 1.27 1.27))))
          (number "8" (effects (font (size 1.27 1.27))))
        )
        (pin passive line (at 15.24 -15.24 180) (length 2.54)
          (name "EP" (effects (font (size 1.27 1.27))))
          (number "9" (effects (font (size 1.27 1.27))))
        )
      )
    )
	(symbol "sdi-mipi-bridge:Oscillator_SMD_27MHz_ABM7" (in_bom yes) (on_board yes)
      (property "Reference" "Y" (at 21.59 -5.08 0)
        (effects (font (size 1.27 1.27) (thickness 0.15)) (justify left bottom))
      )
      (property "Value" "Oscillator_SMD_27MHz_ABM7" (at 21.59 -7.62 0)
        (effects (font (size 1.27 1.27) (thickness 0.15)) (justify left bottom))
      )
      (property "Footprint" "sdi-mipi-bridge-footprints:Oscillator_SMD_Abracon_ABM7-2Pin_6x3.5mm" (at 21.59 -10.16 0)
        (effects (font (size 1.27 1.27) (thickness 0.15)) (justify left bottom) hide)
      )
      (property "Datasheet" "http://www.farnell.com/datasheets/947971.pdf?_ga=2.27685436.1014497200.1574067480-156563690.1566371002&_gac=1.52917722.1572875319.Cj0KCQiAtf_tBRDtARIsAIbAKe0A1M5y_jdFCiNLNrHM5L2GjmDvn_4qnRvhHAD9jBdL9AmoMNThLCoaAjhJEALw_wcB" (at 21.59 -12.7 0)
        (effects (font (size 1.27 1.27) (thickness 0.15)) (justify left bottom) hide)
      )
      (property "MPN" "ABM7-27.000MHZ-D2Y-T" (at 21.59 -15.24 0)
        (effects (font (size 1.27 1.27) (thickness 0.15)) (justify left bottom) hide)
      )
      (property "Manufacturer" "Abracon" (at 21.59 -17.78 0)
        (effects (font (size 1.27 1.27) (thickness 0.15)) (justify left bottom) hide)
      )
      (property "Author" "Antmicro" (at 21.59 -20.32 0)
        (effects (font (size 1.27 1.27) (thickness 0.15)) (justify left bottom) hide)
      )
      (property "License" "Apache-2.0" (at 21.59 -22.86 0)
        (effects (font (size 1.27 1.27) (thickness 0.15)) (justify left bottom) hide)
      )
      (symbol "Oscillator_SMD_27MHz_ABM7_1_1"
        (polyline
          (pts
            (xy 2.54 1.27)
            (xy 2.54 -1.27)
          )
          (stroke (width 0.254) (type default))
          (fill (type background))
        )
        (polyline
          (pts
            (xy 5.08 -1.27)
            (xy 5.08 1.27)
          )
          (stroke (width 0.254) (type default))
          (fill (type background))
        )
        (rectangle (start 3.175 1.905) (end 4.445 -1.905)
          (stroke (width 0.254) (type default))
          (fill (type background))
        )
        (pin passive line (at 0 0 0) (length 2.54)
          (name "~" (effects (font (size 1.27 1.27))))
          (number "1" (effects (font (size 1.27 1.27))))
        )
        (pin passive line (at 7.62 0 180) (length 2.54)
          (name "~" (effects (font (size 1.27 1.27))))
          (number "2" (effects (font (size 1.27 1.27))))
        )
      )
    )
	(symbol "sdi-mipi-bridge:PWR_FLAG" (power) (pin_numbers hide) (pin_names (offset 0) hide) (in_bom yes) (on_board yes)
      (property "Reference" "#FLG" (at 0 1.905 0)
        (effects (font (size 1.27 1.27)) hide)
      )
      (property "Value" "PWR_FLAG" (at 0 3.81 0)
        (effects (font (size 1.27 1.27)))
      )
      (property "Footprint" "" (at 0 0 0)
        (effects (font (size 1.27 1.27)) hide)
      )
      (property "Datasheet" "" (at 0 0 0)
        (effects (font (size 1.27 1.27)) hide)
      )
      (symbol "PWR_FLAG_0_0"
        (pin power_out line (at 0 0 90) (length 0)
          (name "pwr" (effects (font (size 1.27 1.27))))
          (number "1" (effects (font (size 1.27 1.27))))
        )
      )
      (symbol "PWR_FLAG_0_1"
        (polyline
          (pts
            (xy 0 0)
            (xy 0 1.27)
            (xy -1.016 1.905)
            (xy 0 2.54)
            (xy 1.016 1.905)
            (xy 0 1.27)
          )
          (stroke (width 0) (type default))
          (fill (type none))
        )
      )
    )
	(symbol "sdi-mipi-bridge:PinHeader_1x4_P1.27mm_Drill0.7mm" (in_bom yes) (on_board yes)
      (property "Reference" "J" (at 20.32 -5.08 0)
        (effects (font (size 1.27 1.27) (thickness 0.15)) (justify left bottom))
      )
      (property "Value" "PinHeader_1x4_P1.27mm_Drill0.7mm" (at 20.32 -10.16 0)
        (effects (font (size 1.27 1.27) (thickness 0.15)) (justify left bottom) hide)
      )
      (property "Footprint" "sdi-mipi-bridge-footprints:PinHeader_1x4_P1.27mm_Drill0.7mm" (at 20.32 -12.7 0)
        (effects (font (size 1.27 1.27) (thickness 0.15)) (justify left bottom) hide)
      )
      (property "Datasheet" "http://www.farnell.com/datasheets/2605295.pdf" (at 20.32 -15.24 0)
        (effects (font (size 1.27 1.27) (thickness 0.15)) (justify left bottom) hide)
      )
      (property "MPN" "MC-HVT1-S04-G" (at 20.32 -7.62 0)
        (effects (font (size 1.27 1.27) (thickness 0.15)) (justify left bottom))
      )
      (property "Manufacturer" "Multicomp Pro" (at 20.32 -17.78 0)
        (effects (font (size 1.27 1.27) (thickness 0.15)) (justify left bottom) hide)
      )
      (property "Author" "Antmicro" (at 20.32 -20.32 0)
        (effects (font (size 1.27 1.27) (thickness 0.15)) (justify left bottom) hide)
      )
      (property "License" "Apache-2.0" (at 20.32 -22.86 0)
        (effects (font (size 1.27 1.27) (thickness 0.15)) (justify left bottom) hide)
      )
      (property "ki_keywords" "PINSTRIP, HEADER " (at 0 0 0)
        (effects (font (size 1.27 1.27)) hide)
      )
      (property "ki_description" "Pin Header, Board-to-Board, 1.27 mm, 1 Rows, 4 Contacts, Through Hole" (at 0 0 0)
        (effects (font (size 1.27 1.27)) hide)
      )
      (symbol "PinHeader_1x4_P1.27mm_Drill0.7mm_1_1"
        (rectangle (start 4.191 -7.874) (end 3.683 -7.366)
          (stroke (width 0.254) (type default))
          (fill (type background))
        )
        (rectangle (start 4.191 -5.334) (end 3.683 -4.826)
          (stroke (width 0.254) (type default))
          (fill (type background))
        )
        (rectangle (start 4.191 -2.794) (end 3.683 -2.286)
          (stroke (width 0.254) (type default))
          (fill (type background))
        )
        (rectangle (start 4.191 -0.254) (end 3.683 0.254)
          (stroke (width 0.254) (type default))
          (fill (type background))
        )
        (rectangle (start 5.08 -8.89) (end 2.54 1.27)
          (stroke (width 0.254) (type default))
          (fill (type background))
        )
        (pin passive line (at 0 0 0) (length 2.54)
          (name "~" (effects (font (size 1.27 1.27))))
          (number "1" (effects (font (size 1.27 1.27))))
        )
        (pin passive line (at 0 -2.54 0) (length 2.54)
          (name "~" (effects (font (size 1.27 1.27))))
          (number "2" (effects (font (size 1.27 1.27))))
        )
        (pin passive line (at 0 -5.08 0) (length 2.54)
          (name "~" (effects (font (size 1.27 1.27))))
          (number "3" (effects (font (size 1.27 1.27))))
        )
        (pin passive line (at 0 -7.62 0) (length 2.54)
          (name "~" (effects (font (size 1.27 1.27))))
          (number "4" (effects (font (size 1.27 1.27))))
        )
      )
    )
	(symbol "sdi-mipi-bridge:PinHeader_2x5_P1.27mm_Drill0.65mm" (in_bom yes) (on_board yes)
      (property "Reference" "J" (at 25.4 -5.08 0)
        (effects (font (size 1.27 1.27) (thickness 0.15)) (justify left bottom))
      )
      (property "Value" "PinHeader_2x5_P1.27mm_Drill0.65mm" (at 25.4 -10.16 0)
        (effects (font (size 1.27 1.27) (thickness 0.15)) (justify left bottom) hide)
      )
      (property "Footprint" "sdi-mipi-bridge-footprints:PinHeader_2x5_P1.27mm_Drill0.65mm" (at 25.4 -12.7 0)
        (effects (font (size 1.27 1.27) (thickness 0.15)) (justify left bottom) hide)
      )
      (property "Datasheet" "https://www.farnell.com/datasheets/3108040.pdf" (at 25.4 -15.24 0)
        (effects (font (size 1.27 1.27) (thickness 0.15)) (justify left bottom) hide)
      )
      (property "MPN" "2199SB-10G-301523" (at 25.4 -7.62 0)
        (effects (font (size 1.27 1.27) (thickness 0.15)) (justify left bottom))
      )
      (property "Manufacturer" "Multicomp Pro" (at 25.4 -17.78 0)
        (effects (font (size 1.27 1.27) (thickness 0.15)) (justify left bottom) hide)
      )
      (property "Author" "Antmicro" (at 25.4 -20.32 0)
        (effects (font (size 1.27 1.27) (thickness 0.15)) (justify left bottom) hide)
      )
      (property "License" "Apache-2.0" (at 25.4 -22.86 0)
        (effects (font (size 1.27 1.27) (thickness 0.15)) (justify left bottom) hide)
      )
      (property "ki_keywords" "PINSTRIP, HEADER, THT" (at 0 0 0)
        (effects (font (size 1.27 1.27)) hide)
      )
      (property "ki_description" "Pin Header, Board-to-Board, 1.27 mm, 2 Rows, 10 Contacts, Through Hole Straight, 2199SB" (at 0 0 0)
        (effects (font (size 1.27 1.27)) hide)
      )
      (property "ki_fp_filters" "Connector*:*_2x??_*" (at 0 0 0)
        (effects (font (size 1.27 1.27)) hide)
      )
      (symbol "PinHeader_2x5_P1.27mm_Drill0.65mm_1_1"
        (rectangle (start 2.54 1.27) (end 7.62 -11.43)
          (stroke (width 0.254) (type default))
          (fill (type background))
        )
        (rectangle (start 3.556 -9.906) (end 4.064 -10.414)
          (stroke (width 0.254) (type default))
          (fill (type background))
        )
        (rectangle (start 3.556 -7.366) (end 4.064 -7.874)
          (stroke (width 0.254) (type default))
          (fill (type background))
        )
        (rectangle (start 3.556 -4.826) (end 4.064 -5.334)
          (stroke (width 0.254) (type default))
          (fill (type background))
        )
        (rectangle (start 3.556 -2.286) (end 4.064 -2.794)
          (stroke (width 0.254) (type default))
          (fill (type background))
        )
        (rectangle (start 3.556 0.254) (end 4.064 -0.254)
          (stroke (width 0.254) (type default))
          (fill (type background))
        )
        (rectangle (start 6.096 -9.906) (end 6.604 -10.414)
          (stroke (width 0.254) (type default))
          (fill (type background))
        )
        (rectangle (start 6.096 -7.366) (end 6.604 -7.874)
          (stroke (width 0.254) (type default))
          (fill (type background))
        )
        (rectangle (start 6.096 -4.826) (end 6.604 -5.334)
          (stroke (width 0.254) (type default))
          (fill (type background))
        )
        (rectangle (start 6.096 -2.286) (end 6.604 -2.794)
          (stroke (width 0.254) (type default))
          (fill (type background))
        )
        (rectangle (start 6.096 0.254) (end 6.604 -0.254)
          (stroke (width 0.254) (type default))
          (fill (type background))
        )
        (pin passive line (at 0 0 0) (length 2.54)
          (name "~" (effects (font (size 1.27 1.27))))
          (number "1" (effects (font (size 1.27 1.27))))
        )
        (pin passive line (at 10.16 -10.16 180) (length 2.54)
          (name "~" (effects (font (size 1.27 1.27))))
          (number "10" (effects (font (size 1.27 1.27))))
        )
        (pin passive line (at 10.16 0 180) (length 2.54)
          (name "~" (effects (font (size 1.27 1.27))))
          (number "2" (effects (font (size 1.27 1.27))))
        )
        (pin passive line (at 0 -2.54 0) (length 2.54)
          (name "~" (effects (font (size 1.27 1.27))))
          (number "3" (effects (font (size 1.27 1.27))))
        )
        (pin passive line (at 10.16 -2.54 180) (length 2.54)
          (name "~" (effects (font (size 1.27 1.27))))
          (number "4" (effects (font (size 1.27 1.27))))
        )
        (pin passive line (at 0 -5.08 0) (length 2.54)
          (name "~" (effects (font (size 1.27 1.27))))
          (number "5" (effects (font (size 1.27 1.27))))
        )
        (pin passive line (at 10.16 -5.08 180) (length 2.54)
          (name "~" (effects (font (size 1.27 1.27))))
          (number "6" (effects (font (size 1.27 1.27))))
        )
        (pin passive line (at 0 -7.62 0) (length 2.54)
          (name "~" (effects (font (size 1.27 1.27))))
          (number "7" (effects (font (size 1.27 1.27))))
        )
        (pin passive line (at 10.16 -7.62 180) (length 2.54)
          (name "~" (effects (font (size 1.27 1.27))))
          (number "8" (effects (font (size 1.27 1.27))))
        )
        (pin passive line (at 0 -10.16 0) (length 2.54)
          (name "~" (effects (font (size 1.27 1.27))))
          (number "9" (effects (font (size 1.27 1.27))))
        )
      )
    )
	(symbol "sdi-mipi-bridge:R_0R_0402" (pin_numbers hide) (pin_names hide) (in_bom yes) (on_board yes)
      (property "Reference" "R" (at 20.32 -5.08 0)
        (effects (font (size 1.27 1.27) (thickness 0.15)) (justify left bottom))
      )
      (property "Value" "R_0R_0402" (at 20.32 -12.7 0)
        (effects (font (size 1.27 1.27) (thickness 0.15)) (justify left bottom) hide)
      )
      (property "Footprint" "sdi-mipi-bridge-footprints:R_0402_1005Metric" (at 20.32 -15.24 0)
        (effects (font (size 1.27 1.27) (thickness 0.15)) (justify left bottom) hide)
      )
      (property "Datasheet" "https://industrial.panasonic.com/cdbs/www-data/pdf/RDA0000/AOA0000C301.pdf" (at 20.32 -17.78 0)
        (effects (font (size 1.27 1.27) (thickness 0.15)) (justify left bottom) hide)
      )
      (property "MPN" "ERJ2GE0R00X" (at 20.32 -20.32 0)
        (effects (font (size 1.27 1.27) (thickness 0.15)) (justify left bottom) hide)
      )
      (property "Manufacturer" "Panasonic" (at 20.32 -22.86 0)
        (effects (font (size 1.27 1.27) (thickness 0.15)) (justify left bottom) hide)
      )
      (property "License" "Apache-2.0" (at 20.32 -25.4 0)
        (effects (font (size 1.27 1.27) (thickness 0.15)) (justify left bottom) hide)
      )
      (property "Author" "Antmicro" (at 20.32 -27.94 0)
        (effects (font (size 1.27 1.27) (thickness 0.15)) (justify left bottom) hide)
      )
      (property "Val" "0R" (at 20.32 -7.62 0)
        (effects (font (size 1.27 1.27) (thickness 0.15)) (justify left bottom))
      )
      (property "Tolerance" "~" (at 20.32 -10.16 0)
        (effects (font (size 1.27 1.27)) (justify left bottom) hide)
      )
      (property "Current" "1A" (at 20.32 -30.48 0)
        (effects (font (size 1.27 1.27) (thickness 0.15)) (justify left bottom) hide)
      )
      (property "ki_description" "0R resistor in 0402 package with unspecified tolerance" (at 0 0 0)
        (effects (font (size 1.27 1.27)) hide)
      )
      (symbol "R_0R_0402_0_1"
        (rectangle (start 0.635 0.889) (end 4.445 -0.889)
          (stroke (width 0.254) (type default))
          (fill (type none))
        )
      )
      (symbol "R_0R_0402_1_1"
        (pin passive line (at 0 0 0) (length 0.635)
          (name "~" (effects (font (size 1.27 1.27))))
          (number "1" (effects (font (size 1.27 1.27))))
        )
        (pin passive line (at 5.08 0 180) (length 0.635)
          (name "~" (effects (font (size 1.27 1.27))))
          (number "2" (effects (font (size 1.27 1.27))))
        )
      )
    )
	(symbol "sdi-mipi-bridge:R_0R_0402_10" (pin_numbers hide) (pin_names hide) (in_bom yes) (on_board yes)
      (property "Reference" "R" (at 20.32 -5.08 0)
        (effects (font (size 1.27 1.27) (thickness 0.15)) (justify left bottom))
      )
      (property "Value" "R_0R_0402_10" (at 20.32 -12.7 0)
        (effects (font (size 1.27 1.27) (thickness 0.15)) (justify left bottom) hide)
      )
      (property "Footprint" "sdi-mipi-bridge-footprints:R_0402_1005Metric" (at 20.32 -15.24 0)
        (effects (font (size 1.27 1.27) (thickness 0.15)) (justify left bottom) hide)
      )
      (property "Datasheet" "https://industrial.panasonic.com/cdbs/www-data/pdf/RDA0000/AOA0000C301.pdf" (at 20.32 -17.78 0)
        (effects (font (size 1.27 1.27) (thickness 0.15)) (justify left bottom) hide)
      )
      (property "MPN" "ERJ2GE0R00X" (at 20.32 -20.32 0)
        (effects (font (size 1.27 1.27) (thickness 0.15)) (justify left bottom) hide)
      )
      (property "Manufacturer" "Panasonic" (at 20.32 -22.86 0)
        (effects (font (size 1.27 1.27) (thickness 0.15)) (justify left bottom) hide)
      )
      (property "License" "Apache-2.0" (at 20.32 -25.4 0)
        (effects (font (size 1.27 1.27) (thickness 0.15)) (justify left bottom) hide)
      )
      (property "Author" "Antmicro" (at 20.32 -27.94 0)
        (effects (font (size 1.27 1.27) (thickness 0.15)) (justify left bottom) hide)
      )
      (property "Val" "0R" (at 20.32 -7.62 0)
        (effects (font (size 1.27 1.27) (thickness 0.15)) (justify left bottom))
      )
      (property "Tolerance" "~" (at 20.32 -10.16 0)
        (effects (font (size 1.27 1.27)) (justify left bottom) hide)
      )
      (property "Current" "1A" (at 20.32 -30.48 0)
        (effects (font (size 1.27 1.27) (thickness 0.15)) (justify left bottom) hide)
      )
      (property "ki_description" "0R resistor in 0402 package with unspecified tolerance" (at 0 0 0)
        (effects (font (size 1.27 1.27)) hide)
      )
      (symbol "R_0R_0402_10_0_1"
        (rectangle (start 0.635 0.889) (end 4.445 -0.889)
          (stroke (width 0.254) (type default))
          (fill (type none))
        )
      )
      (symbol "R_0R_0402_10_1_1"
        (pin passive line (at 0 0 0) (length 0.635)
          (name "~" (effects (font (size 1.27 1.27))))
          (number "1" (effects (font (size 1.27 1.27))))
        )
        (pin passive line (at 5.08 0 180) (length 0.635)
          (name "~" (effects (font (size 1.27 1.27))))
          (number "2" (effects (font (size 1.27 1.27))))
        )
      )
    )
	(symbol "sdi-mipi-bridge:R_0R_0402_11" (pin_numbers hide) (pin_names hide) (in_bom yes) (on_board yes)
      (property "Reference" "R" (at 20.32 -5.08 0)
        (effects (font (size 1.27 1.27) (thickness 0.15)) (justify left bottom))
      )
      (property "Value" "R_0R_0402_11" (at 20.32 -12.7 0)
        (effects (font (size 1.27 1.27) (thickness 0.15)) (justify left bottom) hide)
      )
      (property "Footprint" "sdi-mipi-bridge-footprints:R_0402_1005Metric" (at 20.32 -15.24 0)
        (effects (font (size 1.27 1.27) (thickness 0.15)) (justify left bottom) hide)
      )
      (property "Datasheet" "https://industrial.panasonic.com/cdbs/www-data/pdf/RDA0000/AOA0000C301.pdf" (at 20.32 -17.78 0)
        (effects (font (size 1.27 1.27) (thickness 0.15)) (justify left bottom) hide)
      )
      (property "MPN" "ERJ2GE0R00X" (at 20.32 -20.32 0)
        (effects (font (size 1.27 1.27) (thickness 0.15)) (justify left bottom) hide)
      )
      (property "Manufacturer" "Panasonic" (at 20.32 -22.86 0)
        (effects (font (size 1.27 1.27) (thickness 0.15)) (justify left bottom) hide)
      )
      (property "License" "Apache-2.0" (at 20.32 -25.4 0)
        (effects (font (size 1.27 1.27) (thickness 0.15)) (justify left bottom) hide)
      )
      (property "Author" "Antmicro" (at 20.32 -27.94 0)
        (effects (font (size 1.27 1.27) (thickness 0.15)) (justify left bottom) hide)
      )
      (property "Val" "0R" (at 20.32 -7.62 0)
        (effects (font (size 1.27 1.27) (thickness 0.15)) (justify left bottom))
      )
      (property "Tolerance" "~" (at 20.32 -10.16 0)
        (effects (font (size 1.27 1.27)) (justify left bottom) hide)
      )
      (property "Current" "1A" (at 20.32 -30.48 0)
        (effects (font (size 1.27 1.27) (thickness 0.15)) (justify left bottom) hide)
      )
      (property "ki_description" "0R resistor in 0402 package with unspecified tolerance" (at 0 0 0)
        (effects (font (size 1.27 1.27)) hide)
      )
      (symbol "R_0R_0402_11_0_1"
        (rectangle (start 0.635 0.889) (end 4.445 -0.889)
          (stroke (width 0.254) (type default))
          (fill (type none))
        )
      )
      (symbol "R_0R_0402_11_1_1"
        (pin passive line (at 0 0 0) (length 0.635)
          (name "~" (effects (font (size 1.27 1.27))))
          (number "1" (effects (font (size 1.27 1.27))))
        )
        (pin passive line (at 5.08 0 180) (length 0.635)
          (name "~" (effects (font (size 1.27 1.27))))
          (number "2" (effects (font (size 1.27 1.27))))
        )
      )
    )
	(symbol "sdi-mipi-bridge:R_0R_0402_12" (pin_numbers hide) (pin_names hide) (in_bom yes) (on_board yes)
      (property "Reference" "R" (at 20.32 -5.08 0)
        (effects (font (size 1.27 1.27) (thickness 0.15)) (justify left bottom))
      )
      (property "Value" "R_0R_0402_12" (at 20.32 -12.7 0)
        (effects (font (size 1.27 1.27) (thickness 0.15)) (justify left bottom) hide)
      )
      (property "Footprint" "sdi-mipi-bridge-footprints:R_0402_1005Metric" (at 20.32 -15.24 0)
        (effects (font (size 1.27 1.27) (thickness 0.15)) (justify left bottom) hide)
      )
      (property "Datasheet" "https://industrial.panasonic.com/cdbs/www-data/pdf/RDA0000/AOA0000C301.pdf" (at 20.32 -17.78 0)
        (effects (font (size 1.27 1.27) (thickness 0.15)) (justify left bottom) hide)
      )
      (property "MPN" "ERJ2GE0R00X" (at 20.32 -20.32 0)
        (effects (font (size 1.27 1.27) (thickness 0.15)) (justify left bottom) hide)
      )
      (property "Manufacturer" "Panasonic" (at 20.32 -22.86 0)
        (effects (font (size 1.27 1.27) (thickness 0.15)) (justify left bottom) hide)
      )
      (property "License" "Apache-2.0" (at 20.32 -25.4 0)
        (effects (font (size 1.27 1.27) (thickness 0.15)) (justify left bottom) hide)
      )
      (property "Author" "Antmicro" (at 20.32 -27.94 0)
        (effects (font (size 1.27 1.27) (thickness 0.15)) (justify left bottom) hide)
      )
      (property "Val" "0R" (at 20.32 -7.62 0)
        (effects (font (size 1.27 1.27) (thickness 0.15)) (justify left bottom))
      )
      (property "Tolerance" "~" (at 20.32 -10.16 0)
        (effects (font (size 1.27 1.27)) (justify left bottom) hide)
      )
      (property "Current" "1A" (at 20.32 -30.48 0)
        (effects (font (size 1.27 1.27) (thickness 0.15)) (justify left bottom) hide)
      )
      (property "ki_description" "0R resistor in 0402 package with unspecified tolerance" (at 0 0 0)
        (effects (font (size 1.27 1.27)) hide)
      )
      (symbol "R_0R_0402_12_0_1"
        (rectangle (start 0.635 0.889) (end 4.445 -0.889)
          (stroke (width 0.254) (type default))
          (fill (type none))
        )
      )
      (symbol "R_0R_0402_12_1_1"
        (pin passive line (at 0 0 0) (length 0.635)
          (name "~" (effects (font (size 1.27 1.27))))
          (number "1" (effects (font (size 1.27 1.27))))
        )
        (pin passive line (at 5.08 0 180) (length 0.635)
          (name "~" (effects (font (size 1.27 1.27))))
          (number "2" (effects (font (size 1.27 1.27))))
        )
      )
    )
	(symbol "sdi-mipi-bridge:R_0R_0402_13" (pin_numbers hide) (pin_names hide) (in_bom yes) (on_board yes)
      (property "Reference" "R" (at 20.32 -5.08 0)
        (effects (font (size 1.27 1.27) (thickness 0.15)) (justify left bottom))
      )
      (property "Value" "R_0R_0402_13" (at 20.32 -12.7 0)
        (effects (font (size 1.27 1.27) (thickness 0.15)) (justify left bottom) hide)
      )
      (property "Footprint" "sdi-mipi-bridge-footprints:R_0402_1005Metric" (at 20.32 -15.24 0)
        (effects (font (size 1.27 1.27) (thickness 0.15)) (justify left bottom) hide)
      )
      (property "Datasheet" "https://industrial.panasonic.com/cdbs/www-data/pdf/RDA0000/AOA0000C301.pdf" (at 20.32 -17.78 0)
        (effects (font (size 1.27 1.27) (thickness 0.15)) (justify left bottom) hide)
      )
      (property "MPN" "ERJ2GE0R00X" (at 20.32 -20.32 0)
        (effects (font (size 1.27 1.27) (thickness 0.15)) (justify left bottom) hide)
      )
      (property "Manufacturer" "Panasonic" (at 20.32 -22.86 0)
        (effects (font (size 1.27 1.27) (thickness 0.15)) (justify left bottom) hide)
      )
      (property "License" "Apache-2.0" (at 20.32 -25.4 0)
        (effects (font (size 1.27 1.27) (thickness 0.15)) (justify left bottom) hide)
      )
      (property "Author" "Antmicro" (at 20.32 -27.94 0)
        (effects (font (size 1.27 1.27) (thickness 0.15)) (justify left bottom) hide)
      )
      (property "Val" "0R" (at 20.32 -7.62 0)
        (effects (font (size 1.27 1.27) (thickness 0.15)) (justify left bottom))
      )
      (property "Tolerance" "~" (at 20.32 -10.16 0)
        (effects (font (size 1.27 1.27)) (justify left bottom) hide)
      )
      (property "Current" "1A" (at 20.32 -30.48 0)
        (effects (font (size 1.27 1.27) (thickness 0.15)) (justify left bottom) hide)
      )
      (property "ki_description" "0R resistor in 0402 package with unspecified tolerance" (at 0 0 0)
        (effects (font (size 1.27 1.27)) hide)
      )
      (symbol "R_0R_0402_13_0_1"
        (rectangle (start 0.635 0.889) (end 4.445 -0.889)
          (stroke (width 0.254) (type default))
          (fill (type none))
        )
      )
      (symbol "R_0R_0402_13_1_1"
        (pin passive line (at 0 0 0) (length 0.635)
          (name "~" (effects (font (size 1.27 1.27))))
          (number "1" (effects (font (size 1.27 1.27))))
        )
        (pin passive line (at 5.08 0 180) (length 0.635)
          (name "~" (effects (font (size 1.27 1.27))))
          (number "2" (effects (font (size 1.27 1.27))))
        )
      )
    )
	(symbol "sdi-mipi-bridge:R_0R_0402_14" (pin_numbers hide) (pin_names hide) (in_bom yes) (on_board yes)
      (property "Reference" "R" (at 20.32 -5.08 0)
        (effects (font (size 1.27 1.27) (thickness 0.15)) (justify left bottom))
      )
      (property "Value" "R_0R_0402_14" (at 20.32 -12.7 0)
        (effects (font (size 1.27 1.27) (thickness 0.15)) (justify left bottom) hide)
      )
      (property "Footprint" "sdi-mipi-bridge-footprints:R_0402_1005Metric" (at 20.32 -15.24 0)
        (effects (font (size 1.27 1.27) (thickness 0.15)) (justify left bottom) hide)
      )
      (property "Datasheet" "https://industrial.panasonic.com/cdbs/www-data/pdf/RDA0000/AOA0000C301.pdf" (at 20.32 -17.78 0)
        (effects (font (size 1.27 1.27) (thickness 0.15)) (justify left bottom) hide)
      )
      (property "MPN" "ERJ2GE0R00X" (at 20.32 -20.32 0)
        (effects (font (size 1.27 1.27) (thickness 0.15)) (justify left bottom) hide)
      )
      (property "Manufacturer" "Panasonic" (at 20.32 -22.86 0)
        (effects (font (size 1.27 1.27) (thickness 0.15)) (justify left bottom) hide)
      )
      (property "License" "Apache-2.0" (at 20.32 -25.4 0)
        (effects (font (size 1.27 1.27) (thickness 0.15)) (justify left bottom) hide)
      )
      (property "Author" "Antmicro" (at 20.32 -27.94 0)
        (effects (font (size 1.27 1.27) (thickness 0.15)) (justify left bottom) hide)
      )
      (property "Val" "0R" (at 20.32 -7.62 0)
        (effects (font (size 1.27 1.27) (thickness 0.15)) (justify left bottom))
      )
      (property "Tolerance" "~" (at 20.32 -10.16 0)
        (effects (font (size 1.27 1.27)) (justify left bottom) hide)
      )
      (property "Current" "1A" (at 20.32 -30.48 0)
        (effects (font (size 1.27 1.27) (thickness 0.15)) (justify left bottom) hide)
      )
      (property "ki_description" "0R resistor in 0402 package with unspecified tolerance" (at 0 0 0)
        (effects (font (size 1.27 1.27)) hide)
      )
      (symbol "R_0R_0402_14_0_1"
        (rectangle (start 0.635 0.889) (end 4.445 -0.889)
          (stroke (width 0.254) (type default))
          (fill (type none))
        )
      )
      (symbol "R_0R_0402_14_1_1"
        (pin passive line (at 0 0 0) (length 0.635)
          (name "~" (effects (font (size 1.27 1.27))))
          (number "1" (effects (font (size 1.27 1.27))))
        )
        (pin passive line (at 5.08 0 180) (length 0.635)
          (name "~" (effects (font (size 1.27 1.27))))
          (number "2" (effects (font (size 1.27 1.27))))
        )
      )
    )
	(symbol "sdi-mipi-bridge:R_0R_0402_15" (pin_numbers hide) (pin_names hide) (in_bom yes) (on_board yes)
      (property "Reference" "R" (at 20.32 -5.08 0)
        (effects (font (size 1.27 1.27) (thickness 0.15)) (justify left bottom))
      )
      (property "Value" "R_0R_0402_15" (at 20.32 -12.7 0)
        (effects (font (size 1.27 1.27) (thickness 0.15)) (justify left bottom) hide)
      )
      (property "Footprint" "sdi-mipi-bridge-footprints:R_0402_1005Metric" (at 20.32 -15.24 0)
        (effects (font (size 1.27 1.27) (thickness 0.15)) (justify left bottom) hide)
      )
      (property "Datasheet" "https://industrial.panasonic.com/cdbs/www-data/pdf/RDA0000/AOA0000C301.pdf" (at 20.32 -17.78 0)
        (effects (font (size 1.27 1.27) (thickness 0.15)) (justify left bottom) hide)
      )
      (property "MPN" "ERJ2GE0R00X" (at 20.32 -20.32 0)
        (effects (font (size 1.27 1.27) (thickness 0.15)) (justify left bottom) hide)
      )
      (property "Manufacturer" "Panasonic" (at 20.32 -22.86 0)
        (effects (font (size 1.27 1.27) (thickness 0.15)) (justify left bottom) hide)
      )
      (property "License" "Apache-2.0" (at 20.32 -25.4 0)
        (effects (font (size 1.27 1.27) (thickness 0.15)) (justify left bottom) hide)
      )
      (property "Author" "Antmicro" (at 20.32 -27.94 0)
        (effects (font (size 1.27 1.27) (thickness 0.15)) (justify left bottom) hide)
      )
      (property "Val" "0R" (at 20.32 -7.62 0)
        (effects (font (size 1.27 1.27) (thickness 0.15)) (justify left bottom))
      )
      (property "Tolerance" "~" (at 20.32 -10.16 0)
        (effects (font (size 1.27 1.27)) (justify left bottom) hide)
      )
      (property "Current" "1A" (at 20.32 -30.48 0)
        (effects (font (size 1.27 1.27) (thickness 0.15)) (justify left bottom) hide)
      )
      (property "ki_description" "0R resistor in 0402 package with unspecified tolerance" (at 0 0 0)
        (effects (font (size 1.27 1.27)) hide)
      )
      (symbol "R_0R_0402_15_0_1"
        (rectangle (start 0.635 0.889) (end 4.445 -0.889)
          (stroke (width 0.254) (type default))
          (fill (type none))
        )
      )
      (symbol "R_0R_0402_15_1_1"
        (pin passive line (at 0 0 0) (length 0.635)
          (name "~" (effects (font (size 1.27 1.27))))
          (number "1" (effects (font (size 1.27 1.27))))
        )
        (pin passive line (at 5.08 0 180) (length 0.635)
          (name "~" (effects (font (size 1.27 1.27))))
          (number "2" (effects (font (size 1.27 1.27))))
        )
      )
    )
	(symbol "sdi-mipi-bridge:R_0R_0402_16" (pin_numbers hide) (pin_names hide) (in_bom yes) (on_board yes)
      (property "Reference" "R" (at 20.32 -5.08 0)
        (effects (font (size 1.27 1.27) (thickness 0.15)) (justify left bottom))
      )
      (property "Value" "R_0R_0402_16" (at 20.32 -12.7 0)
        (effects (font (size 1.27 1.27) (thickness 0.15)) (justify left bottom) hide)
      )
      (property "Footprint" "sdi-mipi-bridge-footprints:R_0402_1005Metric" (at 20.32 -15.24 0)
        (effects (font (size 1.27 1.27) (thickness 0.15)) (justify left bottom) hide)
      )
      (property "Datasheet" "https://industrial.panasonic.com/cdbs/www-data/pdf/RDA0000/AOA0000C301.pdf" (at 20.32 -17.78 0)
        (effects (font (size 1.27 1.27) (thickness 0.15)) (justify left bottom) hide)
      )
      (property "MPN" "ERJ2GE0R00X" (at 20.32 -20.32 0)
        (effects (font (size 1.27 1.27) (thickness 0.15)) (justify left bottom) hide)
      )
      (property "Manufacturer" "Panasonic" (at 20.32 -22.86 0)
        (effects (font (size 1.27 1.27) (thickness 0.15)) (justify left bottom) hide)
      )
      (property "License" "Apache-2.0" (at 20.32 -25.4 0)
        (effects (font (size 1.27 1.27) (thickness 0.15)) (justify left bottom) hide)
      )
      (property "Author" "Antmicro" (at 20.32 -27.94 0)
        (effects (font (size 1.27 1.27) (thickness 0.15)) (justify left bottom) hide)
      )
      (property "Val" "0R" (at 20.32 -7.62 0)
        (effects (font (size 1.27 1.27) (thickness 0.15)) (justify left bottom))
      )
      (property "Tolerance" "~" (at 20.32 -10.16 0)
        (effects (font (size 1.27 1.27)) (justify left bottom) hide)
      )
      (property "Current" "1A" (at 20.32 -30.48 0)
        (effects (font (size 1.27 1.27) (thickness 0.15)) (justify left bottom) hide)
      )
      (property "ki_description" "0R resistor in 0402 package with unspecified tolerance" (at 0 0 0)
        (effects (font (size 1.27 1.27)) hide)
      )
      (symbol "R_0R_0402_16_0_1"
        (rectangle (start 0.635 0.889) (end 4.445 -0.889)
          (stroke (width 0.254) (type default))
          (fill (type none))
        )
      )
      (symbol "R_0R_0402_16_1_1"
        (pin passive line (at 0 0 0) (length 0.635)
          (name "~" (effects (font (size 1.27 1.27))))
          (number "1" (effects (font (size 1.27 1.27))))
        )
        (pin passive line (at 5.08 0 180) (length 0.635)
          (name "~" (effects (font (size 1.27 1.27))))
          (number "2" (effects (font (size 1.27 1.27))))
        )
      )
    )
	(symbol "sdi-mipi-bridge:R_0R_0402_17" (pin_numbers hide) (pin_names hide) (in_bom yes) (on_board yes)
      (property "Reference" "R" (at 20.32 -5.08 0)
        (effects (font (size 1.27 1.27) (thickness 0.15)) (justify left bottom))
      )
      (property "Value" "R_0R_0402_17" (at 20.32 -12.7 0)
        (effects (font (size 1.27 1.27) (thickness 0.15)) (justify left bottom) hide)
      )
      (property "Footprint" "sdi-mipi-bridge-footprints:R_0402_1005Metric" (at 20.32 -15.24 0)
        (effects (font (size 1.27 1.27) (thickness 0.15)) (justify left bottom) hide)
      )
      (property "Datasheet" "https://industrial.panasonic.com/cdbs/www-data/pdf/RDA0000/AOA0000C301.pdf" (at 20.32 -17.78 0)
        (effects (font (size 1.27 1.27) (thickness 0.15)) (justify left bottom) hide)
      )
      (property "MPN" "ERJ2GE0R00X" (at 20.32 -20.32 0)
        (effects (font (size 1.27 1.27) (thickness 0.15)) (justify left bottom) hide)
      )
      (property "Manufacturer" "Panasonic" (at 20.32 -22.86 0)
        (effects (font (size 1.27 1.27) (thickness 0.15)) (justify left bottom) hide)
      )
      (property "License" "Apache-2.0" (at 20.32 -25.4 0)
        (effects (font (size 1.27 1.27) (thickness 0.15)) (justify left bottom) hide)
      )
      (property "Author" "Antmicro" (at 20.32 -27.94 0)
        (effects (font (size 1.27 1.27) (thickness 0.15)) (justify left bottom) hide)
      )
      (property "Val" "0R" (at 20.32 -7.62 0)
        (effects (font (size 1.27 1.27) (thickness 0.15)) (justify left bottom))
      )
      (property "Tolerance" "~" (at 20.32 -10.16 0)
        (effects (font (size 1.27 1.27)) (justify left bottom) hide)
      )
      (property "Current" "1A" (at 20.32 -30.48 0)
        (effects (font (size 1.27 1.27) (thickness 0.15)) (justify left bottom) hide)
      )
      (property "ki_description" "0R resistor in 0402 package with unspecified tolerance" (at 0 0 0)
        (effects (font (size 1.27 1.27)) hide)
      )
      (symbol "R_0R_0402_17_0_1"
        (rectangle (start 0.635 0.889) (end 4.445 -0.889)
          (stroke (width 0.254) (type default))
          (fill (type none))
        )
      )
      (symbol "R_0R_0402_17_1_1"
        (pin passive line (at 0 0 0) (length 0.635)
          (name "~" (effects (font (size 1.27 1.27))))
          (number "1" (effects (font (size 1.27 1.27))))
        )
        (pin passive line (at 5.08 0 180) (length 0.635)
          (name "~" (effects (font (size 1.27 1.27))))
          (number "2" (effects (font (size 1.27 1.27))))
        )
      )
    )
	(symbol "sdi-mipi-bridge:R_0R_0402_18" (pin_numbers hide) (pin_names hide) (in_bom yes) (on_board yes)
      (property "Reference" "R" (at 20.32 -5.08 0)
        (effects (font (size 1.27 1.27) (thickness 0.15)) (justify left bottom))
      )
      (property "Value" "R_0R_0402_18" (at 20.32 -12.7 0)
        (effects (font (size 1.27 1.27) (thickness 0.15)) (justify left bottom) hide)
      )
      (property "Footprint" "sdi-mipi-bridge-footprints:R_0402_1005Metric" (at 20.32 -15.24 0)
        (effects (font (size 1.27 1.27) (thickness 0.15)) (justify left bottom) hide)
      )
      (property "Datasheet" "https://industrial.panasonic.com/cdbs/www-data/pdf/RDA0000/AOA0000C301.pdf" (at 20.32 -17.78 0)
        (effects (font (size 1.27 1.27) (thickness 0.15)) (justify left bottom) hide)
      )
      (property "MPN" "ERJ2GE0R00X" (at 20.32 -20.32 0)
        (effects (font (size 1.27 1.27) (thickness 0.15)) (justify left bottom) hide)
      )
      (property "Manufacturer" "Panasonic" (at 20.32 -22.86 0)
        (effects (font (size 1.27 1.27) (thickness 0.15)) (justify left bottom) hide)
      )
      (property "License" "Apache-2.0" (at 20.32 -25.4 0)
        (effects (font (size 1.27 1.27) (thickness 0.15)) (justify left bottom) hide)
      )
      (property "Author" "Antmicro" (at 20.32 -27.94 0)
        (effects (font (size 1.27 1.27) (thickness 0.15)) (justify left bottom) hide)
      )
      (property "Val" "0R" (at 20.32 -7.62 0)
        (effects (font (size 1.27 1.27) (thickness 0.15)) (justify left bottom))
      )
      (property "Tolerance" "~" (at 20.32 -10.16 0)
        (effects (font (size 1.27 1.27)) (justify left bottom) hide)
      )
      (property "Current" "1A" (at 20.32 -30.48 0)
        (effects (font (size 1.27 1.27) (thickness 0.15)) (justify left bottom) hide)
      )
      (property "ki_description" "0R resistor in 0402 package with unspecified tolerance" (at 0 0 0)
        (effects (font (size 1.27 1.27)) hide)
      )
      (symbol "R_0R_0402_18_0_1"
        (rectangle (start 0.635 0.889) (end 4.445 -0.889)
          (stroke (width 0.254) (type default))
          (fill (type none))
        )
      )
      (symbol "R_0R_0402_18_1_1"
        (pin passive line (at 0 0 0) (length 0.635)
          (name "~" (effects (font (size 1.27 1.27))))
          (number "1" (effects (font (size 1.27 1.27))))
        )
        (pin passive line (at 5.08 0 180) (length 0.635)
          (name "~" (effects (font (size 1.27 1.27))))
          (number "2" (effects (font (size 1.27 1.27))))
        )
      )
    )
	(symbol "sdi-mipi-bridge:R_0R_0402_19" (pin_numbers hide) (pin_names hide) (in_bom yes) (on_board yes)
      (property "Reference" "R" (at 20.32 -5.08 0)
        (effects (font (size 1.27 1.27) (thickness 0.15)) (justify left bottom))
      )
      (property "Value" "R_0R_0402_19" (at 20.32 -12.7 0)
        (effects (font (size 1.27 1.27) (thickness 0.15)) (justify left bottom) hide)
      )
      (property "Footprint" "sdi-mipi-bridge-footprints:R_0402_1005Metric" (at 20.32 -15.24 0)
        (effects (font (size 1.27 1.27) (thickness 0.15)) (justify left bottom) hide)
      )
      (property "Datasheet" "https://industrial.panasonic.com/cdbs/www-data/pdf/RDA0000/AOA0000C301.pdf" (at 20.32 -17.78 0)
        (effects (font (size 1.27 1.27) (thickness 0.15)) (justify left bottom) hide)
      )
      (property "MPN" "ERJ2GE0R00X" (at 20.32 -20.32 0)
        (effects (font (size 1.27 1.27) (thickness 0.15)) (justify left bottom) hide)
      )
      (property "Manufacturer" "Panasonic" (at 20.32 -22.86 0)
        (effects (font (size 1.27 1.27) (thickness 0.15)) (justify left bottom) hide)
      )
      (property "License" "Apache-2.0" (at 20.32 -25.4 0)
        (effects (font (size 1.27 1.27) (thickness 0.15)) (justify left bottom) hide)
      )
      (property "Author" "Antmicro" (at 20.32 -27.94 0)
        (effects (font (size 1.27 1.27) (thickness 0.15)) (justify left bottom) hide)
      )
      (property "Val" "0R" (at 20.32 -7.62 0)
        (effects (font (size 1.27 1.27) (thickness 0.15)) (justify left bottom))
      )
      (property "Tolerance" "~" (at 20.32 -10.16 0)
        (effects (font (size 1.27 1.27)) (justify left bottom) hide)
      )
      (property "Current" "1A" (at 20.32 -30.48 0)
        (effects (font (size 1.27 1.27) (thickness 0.15)) (justify left bottom) hide)
      )
      (property "ki_description" "0R resistor in 0402 package with unspecified tolerance" (at 0 0 0)
        (effects (font (size 1.27 1.27)) hide)
      )
      (symbol "R_0R_0402_19_0_1"
        (rectangle (start 0.635 0.889) (end 4.445 -0.889)
          (stroke (width 0.254) (type default))
          (fill (type none))
        )
      )
      (symbol "R_0R_0402_19_1_1"
        (pin passive line (at 0 0 0) (length 0.635)
          (name "~" (effects (font (size 1.27 1.27))))
          (number "1" (effects (font (size 1.27 1.27))))
        )
        (pin passive line (at 5.08 0 180) (length 0.635)
          (name "~" (effects (font (size 1.27 1.27))))
          (number "2" (effects (font (size 1.27 1.27))))
        )
      )
    )
	(symbol "sdi-mipi-bridge:R_0R_0402_20" (pin_numbers hide) (pin_names hide) (in_bom yes) (on_board yes)
      (property "Reference" "R" (at 20.32 -5.08 0)
        (effects (font (size 1.27 1.27) (thickness 0.15)) (justify left bottom))
      )
      (property "Value" "R_0R_0402_20" (at 20.32 -12.7 0)
        (effects (font (size 1.27 1.27) (thickness 0.15)) (justify left bottom) hide)
      )
      (property "Footprint" "sdi-mipi-bridge-footprints:R_0402_1005Metric" (at 20.32 -15.24 0)
        (effects (font (size 1.27 1.27) (thickness 0.15)) (justify left bottom) hide)
      )
      (property "Datasheet" "https://industrial.panasonic.com/cdbs/www-data/pdf/RDA0000/AOA0000C301.pdf" (at 20.32 -17.78 0)
        (effects (font (size 1.27 1.27) (thickness 0.15)) (justify left bottom) hide)
      )
      (property "MPN" "ERJ2GE0R00X" (at 20.32 -20.32 0)
        (effects (font (size 1.27 1.27) (thickness 0.15)) (justify left bottom) hide)
      )
      (property "Manufacturer" "Panasonic" (at 20.32 -22.86 0)
        (effects (font (size 1.27 1.27) (thickness 0.15)) (justify left bottom) hide)
      )
      (property "License" "Apache-2.0" (at 20.32 -25.4 0)
        (effects (font (size 1.27 1.27) (thickness 0.15)) (justify left bottom) hide)
      )
      (property "Author" "Antmicro" (at 20.32 -27.94 0)
        (effects (font (size 1.27 1.27) (thickness 0.15)) (justify left bottom) hide)
      )
      (property "Val" "0R" (at 20.32 -7.62 0)
        (effects (font (size 1.27 1.27) (thickness 0.15)) (justify left bottom))
      )
      (property "Tolerance" "~" (at 20.32 -10.16 0)
        (effects (font (size 1.27 1.27)) (justify left bottom) hide)
      )
      (property "Current" "1A" (at 20.32 -30.48 0)
        (effects (font (size 1.27 1.27) (thickness 0.15)) (justify left bottom) hide)
      )
      (property "ki_description" "0R resistor in 0402 package with unspecified tolerance" (at 0 0 0)
        (effects (font (size 1.27 1.27)) hide)
      )
      (symbol "R_0R_0402_20_0_1"
        (rectangle (start 0.635 0.889) (end 4.445 -0.889)
          (stroke (width 0.254) (type default))
          (fill (type none))
        )
      )
      (symbol "R_0R_0402_20_1_1"
        (pin passive line (at 0 0 0) (length 0.635)
          (name "~" (effects (font (size 1.27 1.27))))
          (number "1" (effects (font (size 1.27 1.27))))
        )
        (pin passive line (at 5.08 0 180) (length 0.635)
          (name "~" (effects (font (size 1.27 1.27))))
          (number "2" (effects (font (size 1.27 1.27))))
        )
      )
    )
	(symbol "sdi-mipi-bridge:R_0R_0402_21" (pin_numbers hide) (pin_names hide) (in_bom yes) (on_board yes)
      (property "Reference" "R" (at 20.32 -5.08 0)
        (effects (font (size 1.27 1.27) (thickness 0.15)) (justify left bottom))
      )
      (property "Value" "R_0R_0402_21" (at 20.32 -12.7 0)
        (effects (font (size 1.27 1.27) (thickness 0.15)) (justify left bottom) hide)
      )
      (property "Footprint" "sdi-mipi-bridge-footprints:R_0402_1005Metric" (at 20.32 -15.24 0)
        (effects (font (size 1.27 1.27) (thickness 0.15)) (justify left bottom) hide)
      )
      (property "Datasheet" "https://industrial.panasonic.com/cdbs/www-data/pdf/RDA0000/AOA0000C301.pdf" (at 20.32 -17.78 0)
        (effects (font (size 1.27 1.27) (thickness 0.15)) (justify left bottom) hide)
      )
      (property "MPN" "ERJ2GE0R00X" (at 20.32 -20.32 0)
        (effects (font (size 1.27 1.27) (thickness 0.15)) (justify left bottom) hide)
      )
      (property "Manufacturer" "Panasonic" (at 20.32 -22.86 0)
        (effects (font (size 1.27 1.27) (thickness 0.15)) (justify left bottom) hide)
      )
      (property "License" "Apache-2.0" (at 20.32 -25.4 0)
        (effects (font (size 1.27 1.27) (thickness 0.15)) (justify left bottom) hide)
      )
      (property "Author" "Antmicro" (at 20.32 -27.94 0)
        (effects (font (size 1.27 1.27) (thickness 0.15)) (justify left bottom) hide)
      )
      (property "Val" "0R" (at 20.32 -7.62 0)
        (effects (font (size 1.27 1.27) (thickness 0.15)) (justify left bottom))
      )
      (property "Tolerance" "~" (at 20.32 -10.16 0)
        (effects (font (size 1.27 1.27)) (justify left bottom) hide)
      )
      (property "Current" "1A" (at 20.32 -30.48 0)
        (effects (font (size 1.27 1.27) (thickness 0.15)) (justify left bottom) hide)
      )
      (property "ki_description" "0R resistor in 0402 package with unspecified tolerance" (at 0 0 0)
        (effects (font (size 1.27 1.27)) hide)
      )
      (symbol "R_0R_0402_21_0_1"
        (rectangle (start 0.635 0.889) (end 4.445 -0.889)
          (stroke (width 0.254) (type default))
          (fill (type none))
        )
      )
      (symbol "R_0R_0402_21_1_1"
        (pin passive line (at 0 0 0) (length 0.635)
          (name "~" (effects (font (size 1.27 1.27))))
          (number "1" (effects (font (size 1.27 1.27))))
        )
        (pin passive line (at 5.08 0 180) (length 0.635)
          (name "~" (effects (font (size 1.27 1.27))))
          (number "2" (effects (font (size 1.27 1.27))))
        )
      )
    )
	(symbol "sdi-mipi-bridge:R_0R_0402_22" (pin_numbers hide) (pin_names hide) (in_bom yes) (on_board yes)
      (property "Reference" "R" (at 20.32 -5.08 0)
        (effects (font (size 1.27 1.27) (thickness 0.15)) (justify left bottom))
      )
      (property "Value" "R_0R_0402_22" (at 20.32 -12.7 0)
        (effects (font (size 1.27 1.27) (thickness 0.15)) (justify left bottom) hide)
      )
      (property "Footprint" "sdi-mipi-bridge-footprints:R_0402_1005Metric" (at 20.32 -15.24 0)
        (effects (font (size 1.27 1.27) (thickness 0.15)) (justify left bottom) hide)
      )
      (property "Datasheet" "https://industrial.panasonic.com/cdbs/www-data/pdf/RDA0000/AOA0000C301.pdf" (at 20.32 -17.78 0)
        (effects (font (size 1.27 1.27) (thickness 0.15)) (justify left bottom) hide)
      )
      (property "MPN" "ERJ2GE0R00X" (at 20.32 -20.32 0)
        (effects (font (size 1.27 1.27) (thickness 0.15)) (justify left bottom) hide)
      )
      (property "Manufacturer" "Panasonic" (at 20.32 -22.86 0)
        (effects (font (size 1.27 1.27) (thickness 0.15)) (justify left bottom) hide)
      )
      (property "License" "Apache-2.0" (at 20.32 -25.4 0)
        (effects (font (size 1.27 1.27) (thickness 0.15)) (justify left bottom) hide)
      )
      (property "Author" "Antmicro" (at 20.32 -27.94 0)
        (effects (font (size 1.27 1.27) (thickness 0.15)) (justify left bottom) hide)
      )
      (property "Val" "0R" (at 20.32 -7.62 0)
        (effects (font (size 1.27 1.27) (thickness 0.15)) (justify left bottom))
      )
      (property "Tolerance" "~" (at 20.32 -10.16 0)
        (effects (font (size 1.27 1.27)) (justify left bottom) hide)
      )
      (property "Current" "1A" (at 20.32 -30.48 0)
        (effects (font (size 1.27 1.27) (thickness 0.15)) (justify left bottom) hide)
      )
      (property "ki_description" "0R resistor in 0402 package with unspecified tolerance" (at 0 0 0)
        (effects (font (size 1.27 1.27)) hide)
      )
      (symbol "R_0R_0402_22_0_1"
        (rectangle (start 0.635 0.889) (end 4.445 -0.889)
          (stroke (width 0.254) (type default))
          (fill (type none))
        )
      )
      (symbol "R_0R_0402_22_1_1"
        (pin passive line (at 0 0 0) (length 0.635)
          (name "~" (effects (font (size 1.27 1.27))))
          (number "1" (effects (font (size 1.27 1.27))))
        )
        (pin passive line (at 5.08 0 180) (length 0.635)
          (name "~" (effects (font (size 1.27 1.27))))
          (number "2" (effects (font (size 1.27 1.27))))
        )
      )
    )
	(symbol "sdi-mipi-bridge:R_0R_0402_23" (pin_numbers hide) (pin_names hide) (in_bom yes) (on_board yes)
      (property "Reference" "R" (at 20.32 -5.08 0)
        (effects (font (size 1.27 1.27) (thickness 0.15)) (justify left bottom))
      )
      (property "Value" "R_0R_0402_23" (at 20.32 -12.7 0)
        (effects (font (size 1.27 1.27) (thickness 0.15)) (justify left bottom) hide)
      )
      (property "Footprint" "sdi-mipi-bridge-footprints:R_0402_1005Metric" (at 20.32 -15.24 0)
        (effects (font (size 1.27 1.27) (thickness 0.15)) (justify left bottom) hide)
      )
      (property "Datasheet" "https://industrial.panasonic.com/cdbs/www-data/pdf/RDA0000/AOA0000C301.pdf" (at 20.32 -17.78 0)
        (effects (font (size 1.27 1.27) (thickness 0.15)) (justify left bottom) hide)
      )
      (property "MPN" "ERJ2GE0R00X" (at 20.32 -20.32 0)
        (effects (font (size 1.27 1.27) (thickness 0.15)) (justify left bottom) hide)
      )
      (property "Manufacturer" "Panasonic" (at 20.32 -22.86 0)
        (effects (font (size 1.27 1.27) (thickness 0.15)) (justify left bottom) hide)
      )
      (property "License" "Apache-2.0" (at 20.32 -25.4 0)
        (effects (font (size 1.27 1.27) (thickness 0.15)) (justify left bottom) hide)
      )
      (property "Author" "Antmicro" (at 20.32 -27.94 0)
        (effects (font (size 1.27 1.27) (thickness 0.15)) (justify left bottom) hide)
      )
      (property "Val" "0R" (at 20.32 -7.62 0)
        (effects (font (size 1.27 1.27) (thickness 0.15)) (justify left bottom))
      )
      (property "Tolerance" "~" (at 20.32 -10.16 0)
        (effects (font (size 1.27 1.27)) (justify left bottom) hide)
      )
      (property "Current" "1A" (at 20.32 -30.48 0)
        (effects (font (size 1.27 1.27) (thickness 0.15)) (justify left bottom) hide)
      )
      (property "ki_description" "0R resistor in 0402 package with unspecified tolerance" (at 0 0 0)
        (effects (font (size 1.27 1.27)) hide)
      )
      (symbol "R_0R_0402_23_0_1"
        (rectangle (start 0.635 0.889) (end 4.445 -0.889)
          (stroke (width 0.254) (type default))
          (fill (type none))
        )
      )
      (symbol "R_0R_0402_23_1_1"
        (pin passive line (at 0 0 0) (length 0.635)
          (name "~" (effects (font (size 1.27 1.27))))
          (number "1" (effects (font (size 1.27 1.27))))
        )
        (pin passive line (at 5.08 0 180) (length 0.635)
          (name "~" (effects (font (size 1.27 1.27))))
          (number "2" (effects (font (size 1.27 1.27))))
        )
      )
    )
	(symbol "sdi-mipi-bridge:R_0R_0402_24" (pin_numbers hide) (pin_names hide) (in_bom yes) (on_board yes)
      (property "Reference" "R" (at 20.32 -5.08 0)
        (effects (font (size 1.27 1.27) (thickness 0.15)) (justify left bottom))
      )
      (property "Value" "R_0R_0402_24" (at 20.32 -12.7 0)
        (effects (font (size 1.27 1.27) (thickness 0.15)) (justify left bottom) hide)
      )
      (property "Footprint" "sdi-mipi-bridge-footprints:R_0402_1005Metric" (at 20.32 -15.24 0)
        (effects (font (size 1.27 1.27) (thickness 0.15)) (justify left bottom) hide)
      )
      (property "Datasheet" "https://industrial.panasonic.com/cdbs/www-data/pdf/RDA0000/AOA0000C301.pdf" (at 20.32 -17.78 0)
        (effects (font (size 1.27 1.27) (thickness 0.15)) (justify left bottom) hide)
      )
      (property "MPN" "ERJ2GE0R00X" (at 20.32 -20.32 0)
        (effects (font (size 1.27 1.27) (thickness 0.15)) (justify left bottom) hide)
      )
      (property "Manufacturer" "Panasonic" (at 20.32 -22.86 0)
        (effects (font (size 1.27 1.27) (thickness 0.15)) (justify left bottom) hide)
      )
      (property "License" "Apache-2.0" (at 20.32 -25.4 0)
        (effects (font (size 1.27 1.27) (thickness 0.15)) (justify left bottom) hide)
      )
      (property "Author" "Antmicro" (at 20.32 -27.94 0)
        (effects (font (size 1.27 1.27) (thickness 0.15)) (justify left bottom) hide)
      )
      (property "Val" "0R" (at 20.32 -7.62 0)
        (effects (font (size 1.27 1.27) (thickness 0.15)) (justify left bottom))
      )
      (property "Tolerance" "~" (at 20.32 -10.16 0)
        (effects (font (size 1.27 1.27)) (justify left bottom) hide)
      )
      (property "Current" "1A" (at 20.32 -30.48 0)
        (effects (font (size 1.27 1.27) (thickness 0.15)) (justify left bottom) hide)
      )
      (property "ki_description" "0R resistor in 0402 package with unspecified tolerance" (at 0 0 0)
        (effects (font (size 1.27 1.27)) hide)
      )
      (symbol "R_0R_0402_24_0_1"
        (rectangle (start 0.635 0.889) (end 4.445 -0.889)
          (stroke (width 0.254) (type default))
          (fill (type none))
        )
      )
      (symbol "R_0R_0402_24_1_1"
        (pin passive line (at 0 0 0) (length 0.635)
          (name "~" (effects (font (size 1.27 1.27))))
          (number "1" (effects (font (size 1.27 1.27))))
        )
        (pin passive line (at 5.08 0 180) (length 0.635)
          (name "~" (effects (font (size 1.27 1.27))))
          (number "2" (effects (font (size 1.27 1.27))))
        )
      )
    )
	(symbol "sdi-mipi-bridge:R_0R_0402_25" (pin_numbers hide) (pin_names hide) (in_bom yes) (on_board yes)
      (property "Reference" "R" (at 20.32 -5.08 0)
        (effects (font (size 1.27 1.27) (thickness 0.15)) (justify left bottom))
      )
      (property "Value" "R_0R_0402_25" (at 20.32 -12.7 0)
        (effects (font (size 1.27 1.27) (thickness 0.15)) (justify left bottom) hide)
      )
      (property "Footprint" "sdi-mipi-bridge-footprints:R_0402_1005Metric" (at 20.32 -15.24 0)
        (effects (font (size 1.27 1.27) (thickness 0.15)) (justify left bottom) hide)
      )
      (property "Datasheet" "https://industrial.panasonic.com/cdbs/www-data/pdf/RDA0000/AOA0000C301.pdf" (at 20.32 -17.78 0)
        (effects (font (size 1.27 1.27) (thickness 0.15)) (justify left bottom) hide)
      )
      (property "MPN" "ERJ2GE0R00X" (at 20.32 -20.32 0)
        (effects (font (size 1.27 1.27) (thickness 0.15)) (justify left bottom) hide)
      )
      (property "Manufacturer" "Panasonic" (at 20.32 -22.86 0)
        (effects (font (size 1.27 1.27) (thickness 0.15)) (justify left bottom) hide)
      )
      (property "License" "Apache-2.0" (at 20.32 -25.4 0)
        (effects (font (size 1.27 1.27) (thickness 0.15)) (justify left bottom) hide)
      )
      (property "Author" "Antmicro" (at 20.32 -27.94 0)
        (effects (font (size 1.27 1.27) (thickness 0.15)) (justify left bottom) hide)
      )
      (property "Val" "0R" (at 20.32 -7.62 0)
        (effects (font (size 1.27 1.27) (thickness 0.15)) (justify left bottom))
      )
      (property "Tolerance" "~" (at 20.32 -10.16 0)
        (effects (font (size 1.27 1.27)) (justify left bottom) hide)
      )
      (property "Current" "1A" (at 20.32 -30.48 0)
        (effects (font (size 1.27 1.27) (thickness 0.15)) (justify left bottom) hide)
      )
      (property "ki_description" "0R resistor in 0402 package with unspecified tolerance" (at 0 0 0)
        (effects (font (size 1.27 1.27)) hide)
      )
      (symbol "R_0R_0402_25_0_1"
        (rectangle (start 0.635 0.889) (end 4.445 -0.889)
          (stroke (width 0.254) (type default))
          (fill (type none))
        )
      )
      (symbol "R_0R_0402_25_1_1"
        (pin passive line (at 0 0 0) (length 0.635)
          (name "~" (effects (font (size 1.27 1.27))))
          (number "1" (effects (font (size 1.27 1.27))))
        )
        (pin passive line (at 5.08 0 180) (length 0.635)
          (name "~" (effects (font (size 1.27 1.27))))
          (number "2" (effects (font (size 1.27 1.27))))
        )
      )
    )
	(symbol "sdi-mipi-bridge:R_0R_0402_26" (pin_numbers hide) (pin_names hide) (in_bom yes) (on_board yes)
      (property "Reference" "R" (at 20.32 -5.08 0)
        (effects (font (size 1.27 1.27) (thickness 0.15)) (justify left bottom))
      )
      (property "Value" "R_0R_0402_26" (at 20.32 -12.7 0)
        (effects (font (size 1.27 1.27) (thickness 0.15)) (justify left bottom) hide)
      )
      (property "Footprint" "sdi-mipi-bridge-footprints:R_0402_1005Metric" (at 20.32 -15.24 0)
        (effects (font (size 1.27 1.27) (thickness 0.15)) (justify left bottom) hide)
      )
      (property "Datasheet" "https://industrial.panasonic.com/cdbs/www-data/pdf/RDA0000/AOA0000C301.pdf" (at 20.32 -17.78 0)
        (effects (font (size 1.27 1.27) (thickness 0.15)) (justify left bottom) hide)
      )
      (property "MPN" "ERJ2GE0R00X" (at 20.32 -20.32 0)
        (effects (font (size 1.27 1.27) (thickness 0.15)) (justify left bottom) hide)
      )
      (property "Manufacturer" "Panasonic" (at 20.32 -22.86 0)
        (effects (font (size 1.27 1.27) (thickness 0.15)) (justify left bottom) hide)
      )
      (property "License" "Apache-2.0" (at 20.32 -25.4 0)
        (effects (font (size 1.27 1.27) (thickness 0.15)) (justify left bottom) hide)
      )
      (property "Author" "Antmicro" (at 20.32 -27.94 0)
        (effects (font (size 1.27 1.27) (thickness 0.15)) (justify left bottom) hide)
      )
      (property "Val" "0R" (at 20.32 -7.62 0)
        (effects (font (size 1.27 1.27) (thickness 0.15)) (justify left bottom))
      )
      (property "Tolerance" "~" (at 20.32 -10.16 0)
        (effects (font (size 1.27 1.27)) (justify left bottom) hide)
      )
      (property "Current" "1A" (at 20.32 -30.48 0)
        (effects (font (size 1.27 1.27) (thickness 0.15)) (justify left bottom) hide)
      )
      (property "ki_description" "0R resistor in 0402 package with unspecified tolerance" (at 0 0 0)
        (effects (font (size 1.27 1.27)) hide)
      )
      (symbol "R_0R_0402_26_0_1"
        (rectangle (start 0.635 0.889) (end 4.445 -0.889)
          (stroke (width 0.254) (type default))
          (fill (type none))
        )
      )
      (symbol "R_0R_0402_26_1_1"
        (pin passive line (at 0 0 0) (length 0.635)
          (name "~" (effects (font (size 1.27 1.27))))
          (number "1" (effects (font (size 1.27 1.27))))
        )
        (pin passive line (at 5.08 0 180) (length 0.635)
          (name "~" (effects (font (size 1.27 1.27))))
          (number "2" (effects (font (size 1.27 1.27))))
        )
      )
    )
	(symbol "sdi-mipi-bridge:R_0R_0402_27" (pin_numbers hide) (pin_names hide) (in_bom yes) (on_board yes)
      (property "Reference" "R" (at 20.32 -5.08 0)
        (effects (font (size 1.27 1.27) (thickness 0.15)) (justify left bottom))
      )
      (property "Value" "R_0R_0402_27" (at 20.32 -12.7 0)
        (effects (font (size 1.27 1.27) (thickness 0.15)) (justify left bottom) hide)
      )
      (property "Footprint" "sdi-mipi-bridge-footprints:R_0402_1005Metric" (at 20.32 -15.24 0)
        (effects (font (size 1.27 1.27) (thickness 0.15)) (justify left bottom) hide)
      )
      (property "Datasheet" "https://industrial.panasonic.com/cdbs/www-data/pdf/RDA0000/AOA0000C301.pdf" (at 20.32 -17.78 0)
        (effects (font (size 1.27 1.27) (thickness 0.15)) (justify left bottom) hide)
      )
      (property "MPN" "ERJ2GE0R00X" (at 20.32 -20.32 0)
        (effects (font (size 1.27 1.27) (thickness 0.15)) (justify left bottom) hide)
      )
      (property "Manufacturer" "Panasonic" (at 20.32 -22.86 0)
        (effects (font (size 1.27 1.27) (thickness 0.15)) (justify left bottom) hide)
      )
      (property "License" "Apache-2.0" (at 20.32 -25.4 0)
        (effects (font (size 1.27 1.27) (thickness 0.15)) (justify left bottom) hide)
      )
      (property "Author" "Antmicro" (at 20.32 -27.94 0)
        (effects (font (size 1.27 1.27) (thickness 0.15)) (justify left bottom) hide)
      )
      (property "Val" "0R" (at 20.32 -7.62 0)
        (effects (font (size 1.27 1.27) (thickness 0.15)) (justify left bottom))
      )
      (property "Tolerance" "~" (at 20.32 -10.16 0)
        (effects (font (size 1.27 1.27)) (justify left bottom) hide)
      )
      (property "Current" "1A" (at 20.32 -30.48 0)
        (effects (font (size 1.27 1.27) (thickness 0.15)) (justify left bottom) hide)
      )
      (property "ki_description" "0R resistor in 0402 package with unspecified tolerance" (at 0 0 0)
        (effects (font (size 1.27 1.27)) hide)
      )
      (symbol "R_0R_0402_27_0_1"
        (rectangle (start 0.635 0.889) (end 4.445 -0.889)
          (stroke (width 0.254) (type default))
          (fill (type none))
        )
      )
      (symbol "R_0R_0402_27_1_1"
        (pin passive line (at 0 0 0) (length 0.635)
          (name "~" (effects (font (size 1.27 1.27))))
          (number "1" (effects (font (size 1.27 1.27))))
        )
        (pin passive line (at 5.08 0 180) (length 0.635)
          (name "~" (effects (font (size 1.27 1.27))))
          (number "2" (effects (font (size 1.27 1.27))))
        )
      )
    )
	(symbol "sdi-mipi-bridge:R_0R_0402_28" (pin_numbers hide) (pin_names hide) (in_bom yes) (on_board yes)
      (property "Reference" "R" (at 20.32 -5.08 0)
        (effects (font (size 1.27 1.27) (thickness 0.15)) (justify left bottom))
      )
      (property "Value" "R_0R_0402_28" (at 20.32 -12.7 0)
        (effects (font (size 1.27 1.27) (thickness 0.15)) (justify left bottom) hide)
      )
      (property "Footprint" "sdi-mipi-bridge-footprints:R_0402_1005Metric" (at 20.32 -15.24 0)
        (effects (font (size 1.27 1.27) (thickness 0.15)) (justify left bottom) hide)
      )
      (property "Datasheet" "https://industrial.panasonic.com/cdbs/www-data/pdf/RDA0000/AOA0000C301.pdf" (at 20.32 -17.78 0)
        (effects (font (size 1.27 1.27) (thickness 0.15)) (justify left bottom) hide)
      )
      (property "MPN" "ERJ2GE0R00X" (at 20.32 -20.32 0)
        (effects (font (size 1.27 1.27) (thickness 0.15)) (justify left bottom) hide)
      )
      (property "Manufacturer" "Panasonic" (at 20.32 -22.86 0)
        (effects (font (size 1.27 1.27) (thickness 0.15)) (justify left bottom) hide)
      )
      (property "License" "Apache-2.0" (at 20.32 -25.4 0)
        (effects (font (size 1.27 1.27) (thickness 0.15)) (justify left bottom) hide)
      )
      (property "Author" "Antmicro" (at 20.32 -27.94 0)
        (effects (font (size 1.27 1.27) (thickness 0.15)) (justify left bottom) hide)
      )
      (property "Val" "0R" (at 20.32 -7.62 0)
        (effects (font (size 1.27 1.27) (thickness 0.15)) (justify left bottom))
      )
      (property "Tolerance" "~" (at 20.32 -10.16 0)
        (effects (font (size 1.27 1.27)) (justify left bottom) hide)
      )
      (property "Current" "1A" (at 20.32 -30.48 0)
        (effects (font (size 1.27 1.27) (thickness 0.15)) (justify left bottom) hide)
      )
      (property "ki_description" "0R resistor in 0402 package with unspecified tolerance" (at 0 0 0)
        (effects (font (size 1.27 1.27)) hide)
      )
      (symbol "R_0R_0402_28_0_1"
        (rectangle (start 0.635 0.889) (end 4.445 -0.889)
          (stroke (width 0.254) (type default))
          (fill (type none))
        )
      )
      (symbol "R_0R_0402_28_1_1"
        (pin passive line (at 0 0 0) (length 0.635)
          (name "~" (effects (font (size 1.27 1.27))))
          (number "1" (effects (font (size 1.27 1.27))))
        )
        (pin passive line (at 5.08 0 180) (length 0.635)
          (name "~" (effects (font (size 1.27 1.27))))
          (number "2" (effects (font (size 1.27 1.27))))
        )
      )
    )
	(symbol "sdi-mipi-bridge:R_100R_0402" (pin_numbers hide) (pin_names hide) (in_bom yes) (on_board yes)
      (property "Reference" "R" (at 20.32 -5.08 0)
        (effects (font (size 1.27 1.27) (thickness 0.15)) (justify left bottom))
      )
      (property "Value" "R_100R_0402" (at 20.32 -12.7 0)
        (effects (font (size 1.27 1.27) (thickness 0.15)) (justify left bottom) hide)
      )
      (property "Footprint" "sdi-mipi-bridge-footprints:R_0402_1005Metric" (at 20.32 -15.24 0)
        (effects (font (size 1.27 1.27) (thickness 0.15)) (justify left bottom) hide)
      )
      (property "Datasheet" "https://www.bourns.com/docs/product-datasheets/cr.pdf" (at 20.32 -17.78 0)
        (effects (font (size 1.27 1.27) (thickness 0.15)) (justify left bottom) hide)
      )
      (property "MPN" "CR0402-FX-1000GLF" (at 20.32 -20.32 0)
        (effects (font (size 1.27 1.27) (thickness 0.15)) (justify left bottom) hide)
      )
      (property "Manufacturer" "Bourns" (at 20.32 -22.86 0)
        (effects (font (size 1.27 1.27) (thickness 0.15)) (justify left bottom) hide)
      )
      (property "License" "Apache-2.0" (at 20.32 -25.4 0)
        (effects (font (size 1.27 1.27) (thickness 0.15)) (justify left bottom) hide)
      )
      (property "Author" "Antmicro" (at 20.32 -27.94 0)
        (effects (font (size 1.27 1.27) (thickness 0.15)) (justify left bottom) hide)
      )
      (property "Val" "100R" (at 20.32 -7.62 0)
        (effects (font (size 1.27 1.27) (thickness 0.15)) (justify left bottom))
      )
      (property "Tolerance" "1%" (at 20.32 -10.16 0)
        (effects (font (size 1.27 1.27)) (justify left bottom) hide)
      )
      (property "ki_description" "100R resistor in 0402 package with 1% tolerance" (at 0 0 0)
        (effects (font (size 1.27 1.27)) hide)
      )
      (symbol "R_100R_0402_0_1"
        (rectangle (start 0.635 0.889) (end 4.445 -0.889)
          (stroke (width 0.254) (type default))
          (fill (type none))
        )
      )
      (symbol "R_100R_0402_1_1"
        (pin passive line (at 0 0 0) (length 0.635)
          (name "~" (effects (font (size 1.27 1.27))))
          (number "1" (effects (font (size 1.27 1.27))))
        )
        (pin passive line (at 5.08 0 180) (length 0.635)
          (name "~" (effects (font (size 1.27 1.27))))
          (number "2" (effects (font (size 1.27 1.27))))
        )
      )
    )
	(symbol "sdi-mipi-bridge:R_105R_0402" (pin_numbers hide) (pin_names hide) (in_bom yes) (on_board yes)
      (property "Reference" "R" (at 20.32 -5.08 0)
        (effects (font (size 1.27 1.27) (thickness 0.15)) (justify left bottom))
      )
      (property "Value" "R_105R_0402" (at 20.32 -12.7 0)
        (effects (font (size 1.27 1.27) (thickness 0.15)) (justify left bottom) hide)
      )
      (property "Footprint" "sdi-mipi-bridge-footprints:R_0402_1005Metric" (at 20.32 -15.24 0)
        (effects (font (size 1.27 1.27) (thickness 0.15)) (justify left bottom) hide)
      )
      (property "Datasheet" "https://www.bourns.com/docs/product-datasheets/cr.pdf" (at 20.32 -17.78 0)
        (effects (font (size 1.27 1.27) (thickness 0.15)) (justify left bottom) hide)
      )
      (property "MPN" "CR0402-FX-1050GLF" (at 20.32 -20.32 0)
        (effects (font (size 1.27 1.27) (thickness 0.15)) (justify left bottom) hide)
      )
      (property "Manufacturer" "Bourns" (at 20.32 -22.86 0)
        (effects (font (size 1.27 1.27) (thickness 0.15)) (justify left bottom) hide)
      )
      (property "License" "Apache-2.0" (at 20.32 -25.4 0)
        (effects (font (size 1.27 1.27) (thickness 0.15)) (justify left bottom) hide)
      )
      (property "Author" "Antmicro" (at 20.32 -27.94 0)
        (effects (font (size 1.27 1.27) (thickness 0.15)) (justify left bottom) hide)
      )
      (property "Val" "105R" (at 20.32 -7.62 0)
        (effects (font (size 1.27 1.27) (thickness 0.15)) (justify left bottom))
      )
      (property "Tolerance" "1%" (at 20.32 -10.16 0)
        (effects (font (size 1.27 1.27)) (justify left bottom) hide)
      )
      (property "ki_description" "105R resistor in 0402 package with 1% tolerance" (at 0 0 0)
        (effects (font (size 1.27 1.27)) hide)
      )
      (symbol "R_105R_0402_0_1"
        (rectangle (start 0.635 0.889) (end 4.445 -0.889)
          (stroke (width 0.254) (type default))
          (fill (type none))
        )
      )
      (symbol "R_105R_0402_1_1"
        (pin passive line (at 0 0 0) (length 0.635)
          (name "~" (effects (font (size 1.27 1.27))))
          (number "1" (effects (font (size 1.27 1.27))))
        )
        (pin passive line (at 5.08 0 180) (length 0.635)
          (name "~" (effects (font (size 1.27 1.27))))
          (number "2" (effects (font (size 1.27 1.27))))
        )
      )
    )
	(symbol "sdi-mipi-bridge:R_10k_0402" (pin_numbers hide) (pin_names hide) (in_bom yes) (on_board yes)
      (property "Reference" "R" (at 20.32 -5.08 0)
        (effects (font (size 1.27 1.27) (thickness 0.15)) (justify left bottom))
      )
      (property "Value" "R_10k_0402" (at 20.32 -12.7 0)
        (effects (font (size 1.27 1.27) (thickness 0.15)) (justify left bottom) hide)
      )
      (property "Footprint" "sdi-mipi-bridge-footprints:R_0402_1005Metric" (at 20.32 -15.24 0)
        (effects (font (size 1.27 1.27) (thickness 0.15)) (justify left bottom) hide)
      )
      (property "Datasheet" "https://www.bourns.com/docs/product-datasheets/cr.pdf" (at 20.32 -17.78 0)
        (effects (font (size 1.27 1.27) (thickness 0.15)) (justify left bottom) hide)
      )
      (property "MPN" "CR0402-FX-1002GLF" (at 20.32 -20.32 0)
        (effects (font (size 1.27 1.27) (thickness 0.15)) (justify left bottom) hide)
      )
      (property "Manufacturer" "Bourns" (at 20.32 -22.86 0)
        (effects (font (size 1.27 1.27) (thickness 0.15)) (justify left bottom) hide)
      )
      (property "License" "Apache-2.0" (at 20.32 -25.4 0)
        (effects (font (size 1.27 1.27) (thickness 0.15)) (justify left bottom) hide)
      )
      (property "Author" "Antmicro" (at 20.32 -27.94 0)
        (effects (font (size 1.27 1.27) (thickness 0.15)) (justify left bottom) hide)
      )
      (property "Val" "10k" (at 20.32 -7.62 0)
        (effects (font (size 1.27 1.27) (thickness 0.15)) (justify left bottom))
      )
      (property "Tolerance" "1%" (at 20.32 -10.16 0)
        (effects (font (size 1.27 1.27)) (justify left bottom) hide)
      )
      (property "ki_description" "10k resistor in 0402 package with 1% tolerance" (at 0 0 0)
        (effects (font (size 1.27 1.27)) hide)
      )
      (symbol "R_10k_0402_0_1"
        (rectangle (start 0.635 0.889) (end 4.445 -0.889)
          (stroke (width 0.254) (type default))
          (fill (type none))
        )
      )
      (symbol "R_10k_0402_1_1"
        (pin passive line (at 0 0 0) (length 0.635)
          (name "~" (effects (font (size 1.27 1.27))))
          (number "1" (effects (font (size 1.27 1.27))))
        )
        (pin passive line (at 5.08 0 180) (length 0.635)
          (name "~" (effects (font (size 1.27 1.27))))
          (number "2" (effects (font (size 1.27 1.27))))
        )
      )
    )
	(symbol "sdi-mipi-bridge:R_10k_0402_10" (pin_numbers hide) (pin_names hide) (in_bom yes) (on_board yes)
      (property "Reference" "R" (at 20.32 -5.08 0)
        (effects (font (size 1.27 1.27) (thickness 0.15)) (justify left bottom))
      )
      (property "Value" "R_10k_0402_10" (at 20.32 -12.7 0)
        (effects (font (size 1.27 1.27) (thickness 0.15)) (justify left bottom) hide)
      )
      (property "Footprint" "sdi-mipi-bridge-footprints:R_0402_1005Metric" (at 20.32 -15.24 0)
        (effects (font (size 1.27 1.27) (thickness 0.15)) (justify left bottom) hide)
      )
      (property "Datasheet" "https://www.bourns.com/docs/product-datasheets/cr.pdf" (at 20.32 -17.78 0)
        (effects (font (size 1.27 1.27) (thickness 0.15)) (justify left bottom) hide)
      )
      (property "MPN" "CR0402-FX-1002GLF" (at 20.32 -20.32 0)
        (effects (font (size 1.27 1.27) (thickness 0.15)) (justify left bottom) hide)
      )
      (property "Manufacturer" "Bourns" (at 20.32 -22.86 0)
        (effects (font (size 1.27 1.27) (thickness 0.15)) (justify left bottom) hide)
      )
      (property "License" "Apache-2.0" (at 20.32 -25.4 0)
        (effects (font (size 1.27 1.27) (thickness 0.15)) (justify left bottom) hide)
      )
      (property "Author" "Antmicro" (at 20.32 -27.94 0)
        (effects (font (size 1.27 1.27) (thickness 0.15)) (justify left bottom) hide)
      )
      (property "Val" "10k" (at 20.32 -7.62 0)
        (effects (font (size 1.27 1.27) (thickness 0.15)) (justify left bottom))
      )
      (property "Tolerance" "1%" (at 20.32 -10.16 0)
        (effects (font (size 1.27 1.27)) (justify left bottom) hide)
      )
      (property "ki_description" "10k resistor in 0402 package with 1% tolerance" (at 0 0 0)
        (effects (font (size 1.27 1.27)) hide)
      )
      (symbol "R_10k_0402_10_0_1"
        (rectangle (start 0.635 0.889) (end 4.445 -0.889)
          (stroke (width 0.254) (type default))
          (fill (type none))
        )
      )
      (symbol "R_10k_0402_10_1_1"
        (pin passive line (at 0 0 0) (length 0.635)
          (name "~" (effects (font (size 1.27 1.27))))
          (number "1" (effects (font (size 1.27 1.27))))
        )
        (pin passive line (at 5.08 0 180) (length 0.635)
          (name "~" (effects (font (size 1.27 1.27))))
          (number "2" (effects (font (size 1.27 1.27))))
        )
      )
    )
	(symbol "sdi-mipi-bridge:R_10k_0402_11" (pin_numbers hide) (pin_names hide) (in_bom yes) (on_board yes)
      (property "Reference" "R" (at 20.32 -5.08 0)
        (effects (font (size 1.27 1.27) (thickness 0.15)) (justify left bottom))
      )
      (property "Value" "R_10k_0402_11" (at 20.32 -12.7 0)
        (effects (font (size 1.27 1.27) (thickness 0.15)) (justify left bottom) hide)
      )
      (property "Footprint" "sdi-mipi-bridge-footprints:R_0402_1005Metric" (at 20.32 -15.24 0)
        (effects (font (size 1.27 1.27) (thickness 0.15)) (justify left bottom) hide)
      )
      (property "Datasheet" "https://www.bourns.com/docs/product-datasheets/cr.pdf" (at 20.32 -17.78 0)
        (effects (font (size 1.27 1.27) (thickness 0.15)) (justify left bottom) hide)
      )
      (property "MPN" "CR0402-FX-1002GLF" (at 20.32 -20.32 0)
        (effects (font (size 1.27 1.27) (thickness 0.15)) (justify left bottom) hide)
      )
      (property "Manufacturer" "Bourns" (at 20.32 -22.86 0)
        (effects (font (size 1.27 1.27) (thickness 0.15)) (justify left bottom) hide)
      )
      (property "License" "Apache-2.0" (at 20.32 -25.4 0)
        (effects (font (size 1.27 1.27) (thickness 0.15)) (justify left bottom) hide)
      )
      (property "Author" "Antmicro" (at 20.32 -27.94 0)
        (effects (font (size 1.27 1.27) (thickness 0.15)) (justify left bottom) hide)
      )
      (property "Val" "10k" (at 20.32 -7.62 0)
        (effects (font (size 1.27 1.27) (thickness 0.15)) (justify left bottom))
      )
      (property "Tolerance" "1%" (at 20.32 -10.16 0)
        (effects (font (size 1.27 1.27)) (justify left bottom) hide)
      )
      (property "ki_description" "10k resistor in 0402 package with 1% tolerance" (at 0 0 0)
        (effects (font (size 1.27 1.27)) hide)
      )
      (symbol "R_10k_0402_11_0_1"
        (rectangle (start 0.635 0.889) (end 4.445 -0.889)
          (stroke (width 0.254) (type default))
          (fill (type none))
        )
      )
      (symbol "R_10k_0402_11_1_1"
        (pin passive line (at 0 0 0) (length 0.635)
          (name "~" (effects (font (size 1.27 1.27))))
          (number "1" (effects (font (size 1.27 1.27))))
        )
        (pin passive line (at 5.08 0 180) (length 0.635)
          (name "~" (effects (font (size 1.27 1.27))))
          (number "2" (effects (font (size 1.27 1.27))))
        )
      )
    )
	(symbol "sdi-mipi-bridge:R_10k_0402_12" (pin_numbers hide) (pin_names hide) (in_bom yes) (on_board yes)
      (property "Reference" "R" (at 20.32 -5.08 0)
        (effects (font (size 1.27 1.27) (thickness 0.15)) (justify left bottom))
      )
      (property "Value" "R_10k_0402_12" (at 20.32 -12.7 0)
        (effects (font (size 1.27 1.27) (thickness 0.15)) (justify left bottom) hide)
      )
      (property "Footprint" "sdi-mipi-bridge-footprints:R_0402_1005Metric" (at 20.32 -15.24 0)
        (effects (font (size 1.27 1.27) (thickness 0.15)) (justify left bottom) hide)
      )
      (property "Datasheet" "https://www.bourns.com/docs/product-datasheets/cr.pdf" (at 20.32 -17.78 0)
        (effects (font (size 1.27 1.27) (thickness 0.15)) (justify left bottom) hide)
      )
      (property "MPN" "CR0402-FX-1002GLF" (at 20.32 -20.32 0)
        (effects (font (size 1.27 1.27) (thickness 0.15)) (justify left bottom) hide)
      )
      (property "Manufacturer" "Bourns" (at 20.32 -22.86 0)
        (effects (font (size 1.27 1.27) (thickness 0.15)) (justify left bottom) hide)
      )
      (property "License" "Apache-2.0" (at 20.32 -25.4 0)
        (effects (font (size 1.27 1.27) (thickness 0.15)) (justify left bottom) hide)
      )
      (property "Author" "Antmicro" (at 20.32 -27.94 0)
        (effects (font (size 1.27 1.27) (thickness 0.15)) (justify left bottom) hide)
      )
      (property "Val" "10k" (at 20.32 -7.62 0)
        (effects (font (size 1.27 1.27) (thickness 0.15)) (justify left bottom))
      )
      (property "Tolerance" "1%" (at 20.32 -10.16 0)
        (effects (font (size 1.27 1.27)) (justify left bottom) hide)
      )
      (property "ki_description" "10k resistor in 0402 package with 1% tolerance" (at 0 0 0)
        (effects (font (size 1.27 1.27)) hide)
      )
      (symbol "R_10k_0402_12_0_1"
        (rectangle (start 0.635 0.889) (end 4.445 -0.889)
          (stroke (width 0.254) (type default))
          (fill (type none))
        )
      )
      (symbol "R_10k_0402_12_1_1"
        (pin passive line (at 0 0 0) (length 0.635)
          (name "~" (effects (font (size 1.27 1.27))))
          (number "1" (effects (font (size 1.27 1.27))))
        )
        (pin passive line (at 5.08 0 180) (length 0.635)
          (name "~" (effects (font (size 1.27 1.27))))
          (number "2" (effects (font (size 1.27 1.27))))
        )
      )
    )
	(symbol "sdi-mipi-bridge:R_10k_0402_13" (pin_numbers hide) (pin_names hide) (in_bom yes) (on_board yes)
      (property "Reference" "R" (at 20.32 -5.08 0)
        (effects (font (size 1.27 1.27) (thickness 0.15)) (justify left bottom))
      )
      (property "Value" "R_10k_0402_13" (at 20.32 -12.7 0)
        (effects (font (size 1.27 1.27) (thickness 0.15)) (justify left bottom) hide)
      )
      (property "Footprint" "sdi-mipi-bridge-footprints:R_0402_1005Metric" (at 20.32 -15.24 0)
        (effects (font (size 1.27 1.27) (thickness 0.15)) (justify left bottom) hide)
      )
      (property "Datasheet" "https://www.bourns.com/docs/product-datasheets/cr.pdf" (at 20.32 -17.78 0)
        (effects (font (size 1.27 1.27) (thickness 0.15)) (justify left bottom) hide)
      )
      (property "MPN" "CR0402-FX-1002GLF" (at 20.32 -20.32 0)
        (effects (font (size 1.27 1.27) (thickness 0.15)) (justify left bottom) hide)
      )
      (property "Manufacturer" "Bourns" (at 20.32 -22.86 0)
        (effects (font (size 1.27 1.27) (thickness 0.15)) (justify left bottom) hide)
      )
      (property "License" "Apache-2.0" (at 20.32 -25.4 0)
        (effects (font (size 1.27 1.27) (thickness 0.15)) (justify left bottom) hide)
      )
      (property "Author" "Antmicro" (at 20.32 -27.94 0)
        (effects (font (size 1.27 1.27) (thickness 0.15)) (justify left bottom) hide)
      )
      (property "Val" "10k" (at 20.32 -7.62 0)
        (effects (font (size 1.27 1.27) (thickness 0.15)) (justify left bottom))
      )
      (property "Tolerance" "1%" (at 20.32 -10.16 0)
        (effects (font (size 1.27 1.27)) (justify left bottom) hide)
      )
      (property "ki_description" "10k resistor in 0402 package with 1% tolerance" (at 0 0 0)
        (effects (font (size 1.27 1.27)) hide)
      )
      (symbol "R_10k_0402_13_0_1"
        (rectangle (start 0.635 0.889) (end 4.445 -0.889)
          (stroke (width 0.254) (type default))
          (fill (type none))
        )
      )
      (symbol "R_10k_0402_13_1_1"
        (pin passive line (at 0 0 0) (length 0.635)
          (name "~" (effects (font (size 1.27 1.27))))
          (number "1" (effects (font (size 1.27 1.27))))
        )
        (pin passive line (at 5.08 0 180) (length 0.635)
          (name "~" (effects (font (size 1.27 1.27))))
          (number "2" (effects (font (size 1.27 1.27))))
        )
      )
    )
	(symbol "sdi-mipi-bridge:R_10k_0402_14" (pin_numbers hide) (pin_names hide) (in_bom yes) (on_board yes)
      (property "Reference" "R" (at 20.32 -5.08 0)
        (effects (font (size 1.27 1.27) (thickness 0.15)) (justify left bottom))
      )
      (property "Value" "R_10k_0402_14" (at 20.32 -12.7 0)
        (effects (font (size 1.27 1.27) (thickness 0.15)) (justify left bottom) hide)
      )
      (property "Footprint" "sdi-mipi-bridge-footprints:R_0402_1005Metric" (at 20.32 -15.24 0)
        (effects (font (size 1.27 1.27) (thickness 0.15)) (justify left bottom) hide)
      )
      (property "Datasheet" "https://www.bourns.com/docs/product-datasheets/cr.pdf" (at 20.32 -17.78 0)
        (effects (font (size 1.27 1.27) (thickness 0.15)) (justify left bottom) hide)
      )
      (property "MPN" "CR0402-FX-1002GLF" (at 20.32 -20.32 0)
        (effects (font (size 1.27 1.27) (thickness 0.15)) (justify left bottom) hide)
      )
      (property "Manufacturer" "Bourns" (at 20.32 -22.86 0)
        (effects (font (size 1.27 1.27) (thickness 0.15)) (justify left bottom) hide)
      )
      (property "License" "Apache-2.0" (at 20.32 -25.4 0)
        (effects (font (size 1.27 1.27) (thickness 0.15)) (justify left bottom) hide)
      )
      (property "Author" "Antmicro" (at 20.32 -27.94 0)
        (effects (font (size 1.27 1.27) (thickness 0.15)) (justify left bottom) hide)
      )
      (property "Val" "10k" (at 20.32 -7.62 0)
        (effects (font (size 1.27 1.27) (thickness 0.15)) (justify left bottom))
      )
      (property "Tolerance" "1%" (at 20.32 -10.16 0)
        (effects (font (size 1.27 1.27)) (justify left bottom) hide)
      )
      (property "ki_description" "10k resistor in 0402 package with 1% tolerance" (at 0 0 0)
        (effects (font (size 1.27 1.27)) hide)
      )
      (symbol "R_10k_0402_14_0_1"
        (rectangle (start 0.635 0.889) (end 4.445 -0.889)
          (stroke (width 0.254) (type default))
          (fill (type none))
        )
      )
      (symbol "R_10k_0402_14_1_1"
        (pin passive line (at 0 0 0) (length 0.635)
          (name "~" (effects (font (size 1.27 1.27))))
          (number "1" (effects (font (size 1.27 1.27))))
        )
        (pin passive line (at 5.08 0 180) (length 0.635)
          (name "~" (effects (font (size 1.27 1.27))))
          (number "2" (effects (font (size 1.27 1.27))))
        )
      )
    )
	(symbol "sdi-mipi-bridge:R_10k_0402_15" (pin_numbers hide) (pin_names hide) (in_bom yes) (on_board yes)
      (property "Reference" "R" (at 20.32 -5.08 0)
        (effects (font (size 1.27 1.27) (thickness 0.15)) (justify left bottom))
      )
      (property "Value" "R_10k_0402_15" (at 20.32 -12.7 0)
        (effects (font (size 1.27 1.27) (thickness 0.15)) (justify left bottom) hide)
      )
      (property "Footprint" "sdi-mipi-bridge-footprints:R_0402_1005Metric" (at 20.32 -15.24 0)
        (effects (font (size 1.27 1.27) (thickness 0.15)) (justify left bottom) hide)
      )
      (property "Datasheet" "https://www.bourns.com/docs/product-datasheets/cr.pdf" (at 20.32 -17.78 0)
        (effects (font (size 1.27 1.27) (thickness 0.15)) (justify left bottom) hide)
      )
      (property "MPN" "CR0402-FX-1002GLF" (at 20.32 -20.32 0)
        (effects (font (size 1.27 1.27) (thickness 0.15)) (justify left bottom) hide)
      )
      (property "Manufacturer" "Bourns" (at 20.32 -22.86 0)
        (effects (font (size 1.27 1.27) (thickness 0.15)) (justify left bottom) hide)
      )
      (property "License" "Apache-2.0" (at 20.32 -25.4 0)
        (effects (font (size 1.27 1.27) (thickness 0.15)) (justify left bottom) hide)
      )
      (property "Author" "Antmicro" (at 20.32 -27.94 0)
        (effects (font (size 1.27 1.27) (thickness 0.15)) (justify left bottom) hide)
      )
      (property "Val" "10k" (at 20.32 -7.62 0)
        (effects (font (size 1.27 1.27) (thickness 0.15)) (justify left bottom))
      )
      (property "Tolerance" "1%" (at 20.32 -10.16 0)
        (effects (font (size 1.27 1.27)) (justify left bottom) hide)
      )
      (property "ki_description" "10k resistor in 0402 package with 1% tolerance" (at 0 0 0)
        (effects (font (size 1.27 1.27)) hide)
      )
      (symbol "R_10k_0402_15_0_1"
        (rectangle (start 0.635 0.889) (end 4.445 -0.889)
          (stroke (width 0.254) (type default))
          (fill (type none))
        )
      )
      (symbol "R_10k_0402_15_1_1"
        (pin passive line (at 0 0 0) (length 0.635)
          (name "~" (effects (font (size 1.27 1.27))))
          (number "1" (effects (font (size 1.27 1.27))))
        )
        (pin passive line (at 5.08 0 180) (length 0.635)
          (name "~" (effects (font (size 1.27 1.27))))
          (number "2" (effects (font (size 1.27 1.27))))
        )
      )
    )
	(symbol "sdi-mipi-bridge:R_10k_0402_16" (pin_numbers hide) (pin_names hide) (in_bom yes) (on_board yes)
      (property "Reference" "R" (at 20.32 -5.08 0)
        (effects (font (size 1.27 1.27) (thickness 0.15)) (justify left bottom))
      )
      (property "Value" "R_10k_0402_16" (at 20.32 -12.7 0)
        (effects (font (size 1.27 1.27) (thickness 0.15)) (justify left bottom) hide)
      )
      (property "Footprint" "sdi-mipi-bridge-footprints:R_0402_1005Metric" (at 20.32 -15.24 0)
        (effects (font (size 1.27 1.27) (thickness 0.15)) (justify left bottom) hide)
      )
      (property "Datasheet" "https://www.bourns.com/docs/product-datasheets/cr.pdf" (at 20.32 -17.78 0)
        (effects (font (size 1.27 1.27) (thickness 0.15)) (justify left bottom) hide)
      )
      (property "MPN" "CR0402-FX-1002GLF" (at 20.32 -20.32 0)
        (effects (font (size 1.27 1.27) (thickness 0.15)) (justify left bottom) hide)
      )
      (property "Manufacturer" "Bourns" (at 20.32 -22.86 0)
        (effects (font (size 1.27 1.27) (thickness 0.15)) (justify left bottom) hide)
      )
      (property "License" "Apache-2.0" (at 20.32 -25.4 0)
        (effects (font (size 1.27 1.27) (thickness 0.15)) (justify left bottom) hide)
      )
      (property "Author" "Antmicro" (at 20.32 -27.94 0)
        (effects (font (size 1.27 1.27) (thickness 0.15)) (justify left bottom) hide)
      )
      (property "Val" "10k" (at 20.32 -7.62 0)
        (effects (font (size 1.27 1.27) (thickness 0.15)) (justify left bottom))
      )
      (property "Tolerance" "1%" (at 20.32 -10.16 0)
        (effects (font (size 1.27 1.27)) (justify left bottom) hide)
      )
      (property "ki_description" "10k resistor in 0402 package with 1% tolerance" (at 0 0 0)
        (effects (font (size 1.27 1.27)) hide)
      )
      (symbol "R_10k_0402_16_0_1"
        (rectangle (start 0.635 0.889) (end 4.445 -0.889)
          (stroke (width 0.254) (type default))
          (fill (type none))
        )
      )
      (symbol "R_10k_0402_16_1_1"
        (pin passive line (at 0 0 0) (length 0.635)
          (name "~" (effects (font (size 1.27 1.27))))
          (number "1" (effects (font (size 1.27 1.27))))
        )
        (pin passive line (at 5.08 0 180) (length 0.635)
          (name "~" (effects (font (size 1.27 1.27))))
          (number "2" (effects (font (size 1.27 1.27))))
        )
      )
    )
	(symbol "sdi-mipi-bridge:R_10k_0402_17" (pin_numbers hide) (pin_names hide) (in_bom yes) (on_board yes)
      (property "Reference" "R" (at 20.32 -5.08 0)
        (effects (font (size 1.27 1.27) (thickness 0.15)) (justify left bottom))
      )
      (property "Value" "R_10k_0402_17" (at 20.32 -12.7 0)
        (effects (font (size 1.27 1.27) (thickness 0.15)) (justify left bottom) hide)
      )
      (property "Footprint" "sdi-mipi-bridge-footprints:R_0402_1005Metric" (at 20.32 -15.24 0)
        (effects (font (size 1.27 1.27) (thickness 0.15)) (justify left bottom) hide)
      )
      (property "Datasheet" "https://www.bourns.com/docs/product-datasheets/cr.pdf" (at 20.32 -17.78 0)
        (effects (font (size 1.27 1.27) (thickness 0.15)) (justify left bottom) hide)
      )
      (property "MPN" "CR0402-FX-1002GLF" (at 20.32 -20.32 0)
        (effects (font (size 1.27 1.27) (thickness 0.15)) (justify left bottom) hide)
      )
      (property "Manufacturer" "Bourns" (at 20.32 -22.86 0)
        (effects (font (size 1.27 1.27) (thickness 0.15)) (justify left bottom) hide)
      )
      (property "License" "Apache-2.0" (at 20.32 -25.4 0)
        (effects (font (size 1.27 1.27) (thickness 0.15)) (justify left bottom) hide)
      )
      (property "Author" "Antmicro" (at 20.32 -27.94 0)
        (effects (font (size 1.27 1.27) (thickness 0.15)) (justify left bottom) hide)
      )
      (property "Val" "10k" (at 20.32 -7.62 0)
        (effects (font (size 1.27 1.27) (thickness 0.15)) (justify left bottom))
      )
      (property "Tolerance" "1%" (at 20.32 -10.16 0)
        (effects (font (size 1.27 1.27)) (justify left bottom) hide)
      )
      (property "ki_description" "10k resistor in 0402 package with 1% tolerance" (at 0 0 0)
        (effects (font (size 1.27 1.27)) hide)
      )
      (symbol "R_10k_0402_17_0_1"
        (rectangle (start 0.635 0.889) (end 4.445 -0.889)
          (stroke (width 0.254) (type default))
          (fill (type none))
        )
      )
      (symbol "R_10k_0402_17_1_1"
        (pin passive line (at 0 0 0) (length 0.635)
          (name "~" (effects (font (size 1.27 1.27))))
          (number "1" (effects (font (size 1.27 1.27))))
        )
        (pin passive line (at 5.08 0 180) (length 0.635)
          (name "~" (effects (font (size 1.27 1.27))))
          (number "2" (effects (font (size 1.27 1.27))))
        )
      )
    )
	(symbol "sdi-mipi-bridge:R_10k_0402_18" (pin_numbers hide) (pin_names hide) (in_bom yes) (on_board yes)
      (property "Reference" "R" (at 20.32 -5.08 0)
        (effects (font (size 1.27 1.27) (thickness 0.15)) (justify left bottom))
      )
      (property "Value" "R_10k_0402_18" (at 20.32 -12.7 0)
        (effects (font (size 1.27 1.27) (thickness 0.15)) (justify left bottom) hide)
      )
      (property "Footprint" "sdi-mipi-bridge-footprints:R_0402_1005Metric" (at 20.32 -15.24 0)
        (effects (font (size 1.27 1.27) (thickness 0.15)) (justify left bottom) hide)
      )
      (property "Datasheet" "https://www.bourns.com/docs/product-datasheets/cr.pdf" (at 20.32 -17.78 0)
        (effects (font (size 1.27 1.27) (thickness 0.15)) (justify left bottom) hide)
      )
      (property "MPN" "CR0402-FX-1002GLF" (at 20.32 -20.32 0)
        (effects (font (size 1.27 1.27) (thickness 0.15)) (justify left bottom) hide)
      )
      (property "Manufacturer" "Bourns" (at 20.32 -22.86 0)
        (effects (font (size 1.27 1.27) (thickness 0.15)) (justify left bottom) hide)
      )
      (property "License" "Apache-2.0" (at 20.32 -25.4 0)
        (effects (font (size 1.27 1.27) (thickness 0.15)) (justify left bottom) hide)
      )
      (property "Author" "Antmicro" (at 20.32 -27.94 0)
        (effects (font (size 1.27 1.27) (thickness 0.15)) (justify left bottom) hide)
      )
      (property "Val" "10k" (at 20.32 -7.62 0)
        (effects (font (size 1.27 1.27) (thickness 0.15)) (justify left bottom))
      )
      (property "Tolerance" "1%" (at 20.32 -10.16 0)
        (effects (font (size 1.27 1.27)) (justify left bottom) hide)
      )
      (property "ki_description" "10k resistor in 0402 package with 1% tolerance" (at 0 0 0)
        (effects (font (size 1.27 1.27)) hide)
      )
      (symbol "R_10k_0402_18_0_1"
        (rectangle (start 0.635 0.889) (end 4.445 -0.889)
          (stroke (width 0.254) (type default))
          (fill (type none))
        )
      )
      (symbol "R_10k_0402_18_1_1"
        (pin passive line (at 0 0 0) (length 0.635)
          (name "~" (effects (font (size 1.27 1.27))))
          (number "1" (effects (font (size 1.27 1.27))))
        )
        (pin passive line (at 5.08 0 180) (length 0.635)
          (name "~" (effects (font (size 1.27 1.27))))
          (number "2" (effects (font (size 1.27 1.27))))
        )
      )
    )
	(symbol "sdi-mipi-bridge:R_10k_0402_19" (pin_numbers hide) (pin_names hide) (in_bom yes) (on_board yes)
      (property "Reference" "R" (at 20.32 -5.08 0)
        (effects (font (size 1.27 1.27) (thickness 0.15)) (justify left bottom))
      )
      (property "Value" "R_10k_0402_19" (at 20.32 -12.7 0)
        (effects (font (size 1.27 1.27) (thickness 0.15)) (justify left bottom) hide)
      )
      (property "Footprint" "sdi-mipi-bridge-footprints:R_0402_1005Metric" (at 20.32 -15.24 0)
        (effects (font (size 1.27 1.27) (thickness 0.15)) (justify left bottom) hide)
      )
      (property "Datasheet" "https://www.bourns.com/docs/product-datasheets/cr.pdf" (at 20.32 -17.78 0)
        (effects (font (size 1.27 1.27) (thickness 0.15)) (justify left bottom) hide)
      )
      (property "MPN" "CR0402-FX-1002GLF" (at 20.32 -20.32 0)
        (effects (font (size 1.27 1.27) (thickness 0.15)) (justify left bottom) hide)
      )
      (property "Manufacturer" "Bourns" (at 20.32 -22.86 0)
        (effects (font (size 1.27 1.27) (thickness 0.15)) (justify left bottom) hide)
      )
      (property "License" "Apache-2.0" (at 20.32 -25.4 0)
        (effects (font (size 1.27 1.27) (thickness 0.15)) (justify left bottom) hide)
      )
      (property "Author" "Antmicro" (at 20.32 -27.94 0)
        (effects (font (size 1.27 1.27) (thickness 0.15)) (justify left bottom) hide)
      )
      (property "Val" "10k" (at 20.32 -7.62 0)
        (effects (font (size 1.27 1.27) (thickness 0.15)) (justify left bottom))
      )
      (property "Tolerance" "1%" (at 20.32 -10.16 0)
        (effects (font (size 1.27 1.27)) (justify left bottom) hide)
      )
      (property "ki_description" "10k resistor in 0402 package with 1% tolerance" (at 0 0 0)
        (effects (font (size 1.27 1.27)) hide)
      )
      (symbol "R_10k_0402_19_0_1"
        (rectangle (start 0.635 0.889) (end 4.445 -0.889)
          (stroke (width 0.254) (type default))
          (fill (type none))
        )
      )
      (symbol "R_10k_0402_19_1_1"
        (pin passive line (at 0 0 0) (length 0.635)
          (name "~" (effects (font (size 1.27 1.27))))
          (number "1" (effects (font (size 1.27 1.27))))
        )
        (pin passive line (at 5.08 0 180) (length 0.635)
          (name "~" (effects (font (size 1.27 1.27))))
          (number "2" (effects (font (size 1.27 1.27))))
        )
      )
    )
	(symbol "sdi-mipi-bridge:R_10k_0402_20" (pin_numbers hide) (pin_names hide) (in_bom yes) (on_board yes)
      (property "Reference" "R" (at 20.32 -5.08 0)
        (effects (font (size 1.27 1.27) (thickness 0.15)) (justify left bottom))
      )
      (property "Value" "R_10k_0402_20" (at 20.32 -12.7 0)
        (effects (font (size 1.27 1.27) (thickness 0.15)) (justify left bottom) hide)
      )
      (property "Footprint" "sdi-mipi-bridge-footprints:R_0402_1005Metric" (at 20.32 -15.24 0)
        (effects (font (size 1.27 1.27) (thickness 0.15)) (justify left bottom) hide)
      )
      (property "Datasheet" "https://www.bourns.com/docs/product-datasheets/cr.pdf" (at 20.32 -17.78 0)
        (effects (font (size 1.27 1.27) (thickness 0.15)) (justify left bottom) hide)
      )
      (property "MPN" "CR0402-FX-1002GLF" (at 20.32 -20.32 0)
        (effects (font (size 1.27 1.27) (thickness 0.15)) (justify left bottom) hide)
      )
      (property "Manufacturer" "Bourns" (at 20.32 -22.86 0)
        (effects (font (size 1.27 1.27) (thickness 0.15)) (justify left bottom) hide)
      )
      (property "License" "Apache-2.0" (at 20.32 -25.4 0)
        (effects (font (size 1.27 1.27) (thickness 0.15)) (justify left bottom) hide)
      )
      (property "Author" "Antmicro" (at 20.32 -27.94 0)
        (effects (font (size 1.27 1.27) (thickness 0.15)) (justify left bottom) hide)
      )
      (property "Val" "10k" (at 20.32 -7.62 0)
        (effects (font (size 1.27 1.27) (thickness 0.15)) (justify left bottom))
      )
      (property "Tolerance" "1%" (at 20.32 -10.16 0)
        (effects (font (size 1.27 1.27)) (justify left bottom) hide)
      )
      (property "ki_description" "10k resistor in 0402 package with 1% tolerance" (at 0 0 0)
        (effects (font (size 1.27 1.27)) hide)
      )
      (symbol "R_10k_0402_20_0_1"
        (rectangle (start 0.635 0.889) (end 4.445 -0.889)
          (stroke (width 0.254) (type default))
          (fill (type none))
        )
      )
      (symbol "R_10k_0402_20_1_1"
        (pin passive line (at 0 0 0) (length 0.635)
          (name "~" (effects (font (size 1.27 1.27))))
          (number "1" (effects (font (size 1.27 1.27))))
        )
        (pin passive line (at 5.08 0 180) (length 0.635)
          (name "~" (effects (font (size 1.27 1.27))))
          (number "2" (effects (font (size 1.27 1.27))))
        )
      )
    )
	(symbol "sdi-mipi-bridge:R_10k_0402_21" (pin_numbers hide) (pin_names hide) (in_bom yes) (on_board yes)
      (property "Reference" "R" (at 20.32 -5.08 0)
        (effects (font (size 1.27 1.27) (thickness 0.15)) (justify left bottom))
      )
      (property "Value" "R_10k_0402_21" (at 20.32 -12.7 0)
        (effects (font (size 1.27 1.27) (thickness 0.15)) (justify left bottom) hide)
      )
      (property "Footprint" "sdi-mipi-bridge-footprints:R_0402_1005Metric" (at 20.32 -15.24 0)
        (effects (font (size 1.27 1.27) (thickness 0.15)) (justify left bottom) hide)
      )
      (property "Datasheet" "https://www.bourns.com/docs/product-datasheets/cr.pdf" (at 20.32 -17.78 0)
        (effects (font (size 1.27 1.27) (thickness 0.15)) (justify left bottom) hide)
      )
      (property "MPN" "CR0402-FX-1002GLF" (at 20.32 -20.32 0)
        (effects (font (size 1.27 1.27) (thickness 0.15)) (justify left bottom) hide)
      )
      (property "Manufacturer" "Bourns" (at 20.32 -22.86 0)
        (effects (font (size 1.27 1.27) (thickness 0.15)) (justify left bottom) hide)
      )
      (property "License" "Apache-2.0" (at 20.32 -25.4 0)
        (effects (font (size 1.27 1.27) (thickness 0.15)) (justify left bottom) hide)
      )
      (property "Author" "Antmicro" (at 20.32 -27.94 0)
        (effects (font (size 1.27 1.27) (thickness 0.15)) (justify left bottom) hide)
      )
      (property "Val" "10k" (at 20.32 -7.62 0)
        (effects (font (size 1.27 1.27) (thickness 0.15)) (justify left bottom))
      )
      (property "Tolerance" "1%" (at 20.32 -10.16 0)
        (effects (font (size 1.27 1.27)) (justify left bottom) hide)
      )
      (property "ki_description" "10k resistor in 0402 package with 1% tolerance" (at 0 0 0)
        (effects (font (size 1.27 1.27)) hide)
      )
      (symbol "R_10k_0402_21_0_1"
        (rectangle (start 0.635 0.889) (end 4.445 -0.889)
          (stroke (width 0.254) (type default))
          (fill (type none))
        )
      )
      (symbol "R_10k_0402_21_1_1"
        (pin passive line (at 0 0 0) (length 0.635)
          (name "~" (effects (font (size 1.27 1.27))))
          (number "1" (effects (font (size 1.27 1.27))))
        )
        (pin passive line (at 5.08 0 180) (length 0.635)
          (name "~" (effects (font (size 1.27 1.27))))
          (number "2" (effects (font (size 1.27 1.27))))
        )
      )
    )
	(symbol "sdi-mipi-bridge:R_10k_0402_22" (pin_numbers hide) (pin_names hide) (in_bom yes) (on_board yes)
      (property "Reference" "R" (at 20.32 -5.08 0)
        (effects (font (size 1.27 1.27) (thickness 0.15)) (justify left bottom))
      )
      (property "Value" "R_10k_0402_22" (at 20.32 -12.7 0)
        (effects (font (size 1.27 1.27) (thickness 0.15)) (justify left bottom) hide)
      )
      (property "Footprint" "sdi-mipi-bridge-footprints:R_0402_1005Metric" (at 20.32 -15.24 0)
        (effects (font (size 1.27 1.27) (thickness 0.15)) (justify left bottom) hide)
      )
      (property "Datasheet" "https://www.bourns.com/docs/product-datasheets/cr.pdf" (at 20.32 -17.78 0)
        (effects (font (size 1.27 1.27) (thickness 0.15)) (justify left bottom) hide)
      )
      (property "MPN" "CR0402-FX-1002GLF" (at 20.32 -20.32 0)
        (effects (font (size 1.27 1.27) (thickness 0.15)) (justify left bottom) hide)
      )
      (property "Manufacturer" "Bourns" (at 20.32 -22.86 0)
        (effects (font (size 1.27 1.27) (thickness 0.15)) (justify left bottom) hide)
      )
      (property "License" "Apache-2.0" (at 20.32 -25.4 0)
        (effects (font (size 1.27 1.27) (thickness 0.15)) (justify left bottom) hide)
      )
      (property "Author" "Antmicro" (at 20.32 -27.94 0)
        (effects (font (size 1.27 1.27) (thickness 0.15)) (justify left bottom) hide)
      )
      (property "Val" "10k" (at 20.32 -7.62 0)
        (effects (font (size 1.27 1.27) (thickness 0.15)) (justify left bottom))
      )
      (property "Tolerance" "1%" (at 20.32 -10.16 0)
        (effects (font (size 1.27 1.27)) (justify left bottom) hide)
      )
      (property "ki_description" "10k resistor in 0402 package with 1% tolerance" (at 0 0 0)
        (effects (font (size 1.27 1.27)) hide)
      )
      (symbol "R_10k_0402_22_0_1"
        (rectangle (start 0.635 0.889) (end 4.445 -0.889)
          (stroke (width 0.254) (type default))
          (fill (type none))
        )
      )
      (symbol "R_10k_0402_22_1_1"
        (pin passive line (at 0 0 0) (length 0.635)
          (name "~" (effects (font (size 1.27 1.27))))
          (number "1" (effects (font (size 1.27 1.27))))
        )
        (pin passive line (at 5.08 0 180) (length 0.635)
          (name "~" (effects (font (size 1.27 1.27))))
          (number "2" (effects (font (size 1.27 1.27))))
        )
      )
    )
	(symbol "sdi-mipi-bridge:R_10k_0402_23" (pin_numbers hide) (pin_names hide) (in_bom yes) (on_board yes)
      (property "Reference" "R" (at 20.32 -5.08 0)
        (effects (font (size 1.27 1.27) (thickness 0.15)) (justify left bottom))
      )
      (property "Value" "R_10k_0402_23" (at 20.32 -12.7 0)
        (effects (font (size 1.27 1.27) (thickness 0.15)) (justify left bottom) hide)
      )
      (property "Footprint" "sdi-mipi-bridge-footprints:R_0402_1005Metric" (at 20.32 -15.24 0)
        (effects (font (size 1.27 1.27) (thickness 0.15)) (justify left bottom) hide)
      )
      (property "Datasheet" "https://www.bourns.com/docs/product-datasheets/cr.pdf" (at 20.32 -17.78 0)
        (effects (font (size 1.27 1.27) (thickness 0.15)) (justify left bottom) hide)
      )
      (property "MPN" "CR0402-FX-1002GLF" (at 20.32 -20.32 0)
        (effects (font (size 1.27 1.27) (thickness 0.15)) (justify left bottom) hide)
      )
      (property "Manufacturer" "Bourns" (at 20.32 -22.86 0)
        (effects (font (size 1.27 1.27) (thickness 0.15)) (justify left bottom) hide)
      )
      (property "License" "Apache-2.0" (at 20.32 -25.4 0)
        (effects (font (size 1.27 1.27) (thickness 0.15)) (justify left bottom) hide)
      )
      (property "Author" "Antmicro" (at 20.32 -27.94 0)
        (effects (font (size 1.27 1.27) (thickness 0.15)) (justify left bottom) hide)
      )
      (property "Val" "10k" (at 20.32 -7.62 0)
        (effects (font (size 1.27 1.27) (thickness 0.15)) (justify left bottom))
      )
      (property "Tolerance" "1%" (at 20.32 -10.16 0)
        (effects (font (size 1.27 1.27)) (justify left bottom) hide)
      )
      (property "ki_description" "10k resistor in 0402 package with 1% tolerance" (at 0 0 0)
        (effects (font (size 1.27 1.27)) hide)
      )
      (symbol "R_10k_0402_23_0_1"
        (rectangle (start 0.635 0.889) (end 4.445 -0.889)
          (stroke (width 0.254) (type default))
          (fill (type none))
        )
      )
      (symbol "R_10k_0402_23_1_1"
        (pin passive line (at 0 0 0) (length 0.635)
          (name "~" (effects (font (size 1.27 1.27))))
          (number "1" (effects (font (size 1.27 1.27))))
        )
        (pin passive line (at 5.08 0 180) (length 0.635)
          (name "~" (effects (font (size 1.27 1.27))))
          (number "2" (effects (font (size 1.27 1.27))))
        )
      )
    )
	(symbol "sdi-mipi-bridge:R_10k_0402_24" (pin_numbers hide) (pin_names hide) (in_bom yes) (on_board yes)
      (property "Reference" "R" (at 20.32 -5.08 0)
        (effects (font (size 1.27 1.27) (thickness 0.15)) (justify left bottom))
      )
      (property "Value" "R_10k_0402_24" (at 20.32 -12.7 0)
        (effects (font (size 1.27 1.27) (thickness 0.15)) (justify left bottom) hide)
      )
      (property "Footprint" "sdi-mipi-bridge-footprints:R_0402_1005Metric" (at 20.32 -15.24 0)
        (effects (font (size 1.27 1.27) (thickness 0.15)) (justify left bottom) hide)
      )
      (property "Datasheet" "https://www.bourns.com/docs/product-datasheets/cr.pdf" (at 20.32 -17.78 0)
        (effects (font (size 1.27 1.27) (thickness 0.15)) (justify left bottom) hide)
      )
      (property "MPN" "CR0402-FX-1002GLF" (at 20.32 -20.32 0)
        (effects (font (size 1.27 1.27) (thickness 0.15)) (justify left bottom) hide)
      )
      (property "Manufacturer" "Bourns" (at 20.32 -22.86 0)
        (effects (font (size 1.27 1.27) (thickness 0.15)) (justify left bottom) hide)
      )
      (property "License" "Apache-2.0" (at 20.32 -25.4 0)
        (effects (font (size 1.27 1.27) (thickness 0.15)) (justify left bottom) hide)
      )
      (property "Author" "Antmicro" (at 20.32 -27.94 0)
        (effects (font (size 1.27 1.27) (thickness 0.15)) (justify left bottom) hide)
      )
      (property "Val" "10k" (at 20.32 -7.62 0)
        (effects (font (size 1.27 1.27) (thickness 0.15)) (justify left bottom))
      )
      (property "Tolerance" "1%" (at 20.32 -10.16 0)
        (effects (font (size 1.27 1.27)) (justify left bottom) hide)
      )
      (property "ki_description" "10k resistor in 0402 package with 1% tolerance" (at 0 0 0)
        (effects (font (size 1.27 1.27)) hide)
      )
      (symbol "R_10k_0402_24_0_1"
        (rectangle (start 0.635 0.889) (end 4.445 -0.889)
          (stroke (width 0.254) (type default))
          (fill (type none))
        )
      )
      (symbol "R_10k_0402_24_1_1"
        (pin passive line (at 0 0 0) (length 0.635)
          (name "~" (effects (font (size 1.27 1.27))))
          (number "1" (effects (font (size 1.27 1.27))))
        )
        (pin passive line (at 5.08 0 180) (length 0.635)
          (name "~" (effects (font (size 1.27 1.27))))
          (number "2" (effects (font (size 1.27 1.27))))
        )
      )
    )
	(symbol "sdi-mipi-bridge:R_10k_0402_25" (pin_numbers hide) (pin_names hide) (in_bom yes) (on_board yes)
      (property "Reference" "R" (at 20.32 -5.08 0)
        (effects (font (size 1.27 1.27) (thickness 0.15)) (justify left bottom))
      )
      (property "Value" "R_10k_0402_25" (at 20.32 -12.7 0)
        (effects (font (size 1.27 1.27) (thickness 0.15)) (justify left bottom) hide)
      )
      (property "Footprint" "sdi-mipi-bridge-footprints:R_0402_1005Metric" (at 20.32 -15.24 0)
        (effects (font (size 1.27 1.27) (thickness 0.15)) (justify left bottom) hide)
      )
      (property "Datasheet" "https://www.bourns.com/docs/product-datasheets/cr.pdf" (at 20.32 -17.78 0)
        (effects (font (size 1.27 1.27) (thickness 0.15)) (justify left bottom) hide)
      )
      (property "MPN" "CR0402-FX-1002GLF" (at 20.32 -20.32 0)
        (effects (font (size 1.27 1.27) (thickness 0.15)) (justify left bottom) hide)
      )
      (property "Manufacturer" "Bourns" (at 20.32 -22.86 0)
        (effects (font (size 1.27 1.27) (thickness 0.15)) (justify left bottom) hide)
      )
      (property "License" "Apache-2.0" (at 20.32 -25.4 0)
        (effects (font (size 1.27 1.27) (thickness 0.15)) (justify left bottom) hide)
      )
      (property "Author" "Antmicro" (at 20.32 -27.94 0)
        (effects (font (size 1.27 1.27) (thickness 0.15)) (justify left bottom) hide)
      )
      (property "Val" "10k" (at 20.32 -7.62 0)
        (effects (font (size 1.27 1.27) (thickness 0.15)) (justify left bottom))
      )
      (property "Tolerance" "1%" (at 20.32 -10.16 0)
        (effects (font (size 1.27 1.27)) (justify left bottom) hide)
      )
      (property "ki_description" "10k resistor in 0402 package with 1% tolerance" (at 0 0 0)
        (effects (font (size 1.27 1.27)) hide)
      )
      (symbol "R_10k_0402_25_0_1"
        (rectangle (start 0.635 0.889) (end 4.445 -0.889)
          (stroke (width 0.254) (type default))
          (fill (type none))
        )
      )
      (symbol "R_10k_0402_25_1_1"
        (pin passive line (at 0 0 0) (length 0.635)
          (name "~" (effects (font (size 1.27 1.27))))
          (number "1" (effects (font (size 1.27 1.27))))
        )
        (pin passive line (at 5.08 0 180) (length 0.635)
          (name "~" (effects (font (size 1.27 1.27))))
          (number "2" (effects (font (size 1.27 1.27))))
        )
      )
    )
	(symbol "sdi-mipi-bridge:R_120k_0402" (pin_numbers hide) (pin_names hide) (in_bom yes) (on_board yes)
      (property "Reference" "R" (at 20.32 -5.08 0)
        (effects (font (size 1.27 1.27) (thickness 0.15)) (justify left bottom))
      )
      (property "Value" "R_120k_0402" (at 20.32 -12.7 0)
        (effects (font (size 1.27 1.27) (thickness 0.15)) (justify left bottom) hide)
      )
      (property "Footprint" "sdi-mipi-bridge-footprints:R_0402_1005Metric" (at 20.32 -15.24 0)
        (effects (font (size 1.27 1.27) (thickness 0.15)) (justify left bottom) hide)
      )
      (property "Datasheet" "https://www.bourns.com/docs/product-datasheets/cr.pdf" (at 20.32 -17.78 0)
        (effects (font (size 1.27 1.27) (thickness 0.15)) (justify left bottom) hide)
      )
      (property "MPN" "CR0402-FX-1203GLF" (at 20.32 -20.32 0)
        (effects (font (size 1.27 1.27) (thickness 0.15)) (justify left bottom) hide)
      )
      (property "Manufacturer" "Bourns" (at 20.32 -22.86 0)
        (effects (font (size 1.27 1.27) (thickness 0.15)) (justify left bottom) hide)
      )
      (property "License" "Apache-2.0" (at 20.32 -25.4 0)
        (effects (font (size 1.27 1.27) (thickness 0.15)) (justify left bottom) hide)
      )
      (property "Author" "Antmicro" (at 20.32 -27.94 0)
        (effects (font (size 1.27 1.27) (thickness 0.15)) (justify left bottom) hide)
      )
      (property "Val" "120k" (at 20.32 -7.62 0)
        (effects (font (size 1.27 1.27) (thickness 0.15)) (justify left bottom))
      )
      (property "Tolerance" "1%" (at 20.32 -10.16 0)
        (effects (font (size 1.27 1.27)) (justify left bottom) hide)
      )
      (property "ki_description" "120k resistor in 0402 package with 1% tolerance" (at 0 0 0)
        (effects (font (size 1.27 1.27)) hide)
      )
      (symbol "R_120k_0402_0_1"
        (rectangle (start 0.635 0.889) (end 4.445 -0.889)
          (stroke (width 0.254) (type default))
          (fill (type none))
        )
      )
      (symbol "R_120k_0402_1_1"
        (pin passive line (at 0 0 0) (length 0.635)
          (name "~" (effects (font (size 1.27 1.27))))
          (number "1" (effects (font (size 1.27 1.27))))
        )
        (pin passive line (at 5.08 0 180) (length 0.635)
          (name "~" (effects (font (size 1.27 1.27))))
          (number "2" (effects (font (size 1.27 1.27))))
        )
      )
    )
	(symbol "sdi-mipi-bridge:R_22R_0402" (pin_numbers hide) (pin_names hide) (in_bom yes) (on_board yes)
      (property "Reference" "R" (at 20.32 -5.08 0)
        (effects (font (size 1.27 1.27) (thickness 0.15)) (justify left bottom))
      )
      (property "Value" "R_22R_0402" (at 20.32 -12.7 0)
        (effects (font (size 1.27 1.27) (thickness 0.15)) (justify left bottom) hide)
      )
      (property "Footprint" "sdi-mipi-bridge-footprints:R_0402_1005Metric" (at 20.32 -15.24 0)
        (effects (font (size 1.27 1.27) (thickness 0.15)) (justify left bottom) hide)
      )
      (property "Datasheet" "https://www.bourns.com/docs/product-datasheets/cr.pdf" (at 20.32 -17.78 0)
        (effects (font (size 1.27 1.27) (thickness 0.15)) (justify left bottom) hide)
      )
      (property "MPN" "CR0402-FX-22R0GLF" (at 20.32 -20.32 0)
        (effects (font (size 1.27 1.27) (thickness 0.15)) (justify left bottom) hide)
      )
      (property "Manufacturer" "Bourns" (at 20.32 -22.86 0)
        (effects (font (size 1.27 1.27) (thickness 0.15)) (justify left bottom) hide)
      )
      (property "License" "Apache-2.0" (at 20.32 -25.4 0)
        (effects (font (size 1.27 1.27) (thickness 0.15)) (justify left bottom) hide)
      )
      (property "Author" "Antmicro" (at 20.32 -27.94 0)
        (effects (font (size 1.27 1.27) (thickness 0.15)) (justify left bottom) hide)
      )
      (property "Val" "22R" (at 20.32 -7.62 0)
        (effects (font (size 1.27 1.27) (thickness 0.15)) (justify left bottom))
      )
      (property "Tolerance" "1%" (at 20.32 -10.16 0)
        (effects (font (size 1.27 1.27)) (justify left bottom) hide)
      )
      (property "ki_description" "22R resistor in 0402 package with 1% tolerance" (at 0 0 0)
        (effects (font (size 1.27 1.27)) hide)
      )
      (symbol "R_22R_0402_0_1"
        (rectangle (start 0.635 0.889) (end 4.445 -0.889)
          (stroke (width 0.254) (type default))
          (fill (type none))
        )
      )
      (symbol "R_22R_0402_1_1"
        (pin passive line (at 0 0 0) (length 0.635)
          (name "~" (effects (font (size 1.27 1.27))))
          (number "1" (effects (font (size 1.27 1.27))))
        )
        (pin passive line (at 5.08 0 180) (length 0.635)
          (name "~" (effects (font (size 1.27 1.27))))
          (number "2" (effects (font (size 1.27 1.27))))
        )
      )
    )
	(symbol "sdi-mipi-bridge:R_2k2_0402" (pin_numbers hide) (pin_names hide) (in_bom yes) (on_board yes)
      (property "Reference" "R" (at 20.32 -5.08 0)
        (effects (font (size 1.27 1.27) (thickness 0.15)) (justify left bottom))
      )
      (property "Value" "R_2k2_0402" (at 20.32 -12.7 0)
        (effects (font (size 1.27 1.27) (thickness 0.15)) (justify left bottom) hide)
      )
      (property "Footprint" "sdi-mipi-bridge-footprints:R_0402_1005Metric" (at 20.32 -15.24 0)
        (effects (font (size 1.27 1.27) (thickness 0.15)) (justify left bottom) hide)
      )
      (property "Datasheet" "https://www.bourns.com/docs/product-datasheets/cr.pdf" (at 20.32 -17.78 0)
        (effects (font (size 1.27 1.27) (thickness 0.15)) (justify left bottom) hide)
      )
      (property "MPN" "CR0402-FX-2201GLF" (at 20.32 -20.32 0)
        (effects (font (size 1.27 1.27) (thickness 0.15)) (justify left bottom) hide)
      )
      (property "Manufacturer" "Bourns" (at 20.32 -22.86 0)
        (effects (font (size 1.27 1.27) (thickness 0.15)) (justify left bottom) hide)
      )
      (property "License" "Apache-2.0" (at 20.32 -25.4 0)
        (effects (font (size 1.27 1.27) (thickness 0.15)) (justify left bottom) hide)
      )
      (property "Author" "Antmicro" (at 20.32 -27.94 0)
        (effects (font (size 1.27 1.27) (thickness 0.15)) (justify left bottom) hide)
      )
      (property "Val" "2k2" (at 20.32 -7.62 0)
        (effects (font (size 1.27 1.27) (thickness 0.15)) (justify left bottom))
      )
      (property "Tolerance" "1%" (at 20.32 -10.16 0)
        (effects (font (size 1.27 1.27)) (justify left bottom) hide)
      )
      (property "ki_description" "2k2 resistor in 0402 package with 1% tolerance" (at 0 0 0)
        (effects (font (size 1.27 1.27)) hide)
      )
      (symbol "R_2k2_0402_0_1"
        (rectangle (start 0.635 0.889) (end 4.445 -0.889)
          (stroke (width 0.254) (type default))
          (fill (type none))
        )
      )
      (symbol "R_2k2_0402_1_1"
        (pin passive line (at 0 0 0) (length 0.635)
          (name "~" (effects (font (size 1.27 1.27))))
          (number "1" (effects (font (size 1.27 1.27))))
        )
        (pin passive line (at 5.08 0 180) (length 0.635)
          (name "~" (effects (font (size 1.27 1.27))))
          (number "2" (effects (font (size 1.27 1.27))))
        )
      )
    )
	(symbol "sdi-mipi-bridge:R_30R_0402" (pin_numbers hide) (pin_names hide) (in_bom yes) (on_board yes)
      (property "Reference" "R" (at 20.32 -5.08 0)
        (effects (font (size 1.27 1.27) (thickness 0.15)) (justify left bottom))
      )
      (property "Value" "R_30R_0402" (at 20.32 -12.7 0)
        (effects (font (size 1.27 1.27) (thickness 0.15)) (justify left bottom) hide)
      )
      (property "Footprint" "sdi-mipi-bridge-footprints:R_0402_1005Metric" (at 20.32 -15.24 0)
        (effects (font (size 1.27 1.27) (thickness 0.15)) (justify left bottom) hide)
      )
      (property "Datasheet" "https://www.bourns.com/docs/product-datasheets/cr.pdf" (at 20.32 -17.78 0)
        (effects (font (size 1.27 1.27) (thickness 0.15)) (justify left bottom) hide)
      )
      (property "MPN" "CR0402-FX-30R0GLF" (at 20.32 -20.32 0)
        (effects (font (size 1.27 1.27) (thickness 0.15)) (justify left bottom) hide)
      )
      (property "Manufacturer" "Bourns" (at 20.32 -22.86 0)
        (effects (font (size 1.27 1.27) (thickness 0.15)) (justify left bottom) hide)
      )
      (property "License" "Apache-2.0" (at 20.32 -25.4 0)
        (effects (font (size 1.27 1.27) (thickness 0.15)) (justify left bottom) hide)
      )
      (property "Author" "Antmicro" (at 20.32 -27.94 0)
        (effects (font (size 1.27 1.27) (thickness 0.15)) (justify left bottom) hide)
      )
      (property "Val" "30R" (at 20.32 -7.62 0)
        (effects (font (size 1.27 1.27) (thickness 0.15)) (justify left bottom))
      )
      (property "Tolerance" "1%" (at 20.32 -10.16 0)
        (effects (font (size 1.27 1.27)) (justify left bottom) hide)
      )
      (property "ki_description" "30R resistor in 0402 package with 1% tolerance" (at 0 0 0)
        (effects (font (size 1.27 1.27)) hide)
      )
      (symbol "R_30R_0402_0_1"
        (rectangle (start 0.635 0.889) (end 4.445 -0.889)
          (stroke (width 0.254) (type default))
          (fill (type none))
        )
      )
      (symbol "R_30R_0402_1_1"
        (pin passive line (at 0 0 0) (length 0.635)
          (name "~" (effects (font (size 1.27 1.27))))
          (number "1" (effects (font (size 1.27 1.27))))
        )
        (pin passive line (at 5.08 0 180) (length 0.635)
          (name "~" (effects (font (size 1.27 1.27))))
          (number "2" (effects (font (size 1.27 1.27))))
        )
      )
    )
	(symbol "sdi-mipi-bridge:R_37R4_0402" (pin_numbers hide) (pin_names hide) (in_bom yes) (on_board yes)
      (property "Reference" "R" (at 20.32 -5.08 0)
        (effects (font (size 1.27 1.27) (thickness 0.15)) (justify left bottom))
      )
      (property "Value" "R_37R4_0402" (at 20.32 -12.7 0)
        (effects (font (size 1.27 1.27) (thickness 0.15)) (justify left bottom) hide)
      )
      (property "Footprint" "sdi-mipi-bridge-footprints:R_0402_1005Metric" (at 20.32 -15.24 0)
        (effects (font (size 1.27 1.27) (thickness 0.15)) (justify left bottom) hide)
      )
      (property "Datasheet" "https://www.bourns.com/docs/product-datasheets/cr.pdf" (at 20.32 -17.78 0)
        (effects (font (size 1.27 1.27) (thickness 0.15)) (justify left bottom) hide)
      )
      (property "MPN" "CR0402-FX-37R4GLF" (at 20.32 -20.32 0)
        (effects (font (size 1.27 1.27) (thickness 0.15)) (justify left bottom) hide)
      )
      (property "Manufacturer" "Bourns" (at 20.32 -22.86 0)
        (effects (font (size 1.27 1.27) (thickness 0.15)) (justify left bottom) hide)
      )
      (property "License" "Apache-2.0" (at 20.32 -25.4 0)
        (effects (font (size 1.27 1.27) (thickness 0.15)) (justify left bottom) hide)
      )
      (property "Author" "Antmicro" (at 20.32 -27.94 0)
        (effects (font (size 1.27 1.27) (thickness 0.15)) (justify left bottom) hide)
      )
      (property "Val" "37R4" (at 20.32 -7.62 0)
        (effects (font (size 1.27 1.27) (thickness 0.15)) (justify left bottom))
      )
      (property "Tolerance" "1%" (at 20.32 -10.16 0)
        (effects (font (size 1.27 1.27)) (justify left bottom) hide)
      )
      (property "ki_description" "37R4 resistor in 0402 package with 1% tolerance" (at 0 0 0)
        (effects (font (size 1.27 1.27)) hide)
      )
      (symbol "R_37R4_0402_0_1"
        (rectangle (start 0.635 0.889) (end 4.445 -0.889)
          (stroke (width 0.254) (type default))
          (fill (type none))
        )
      )
      (symbol "R_37R4_0402_1_1"
        (pin passive line (at 0 0 0) (length 0.635)
          (name "~" (effects (font (size 1.27 1.27))))
          (number "1" (effects (font (size 1.27 1.27))))
        )
        (pin passive line (at 5.08 0 180) (length 0.635)
          (name "~" (effects (font (size 1.27 1.27))))
          (number "2" (effects (font (size 1.27 1.27))))
        )
      )
    )
	(symbol "sdi-mipi-bridge:R_4k7_0402" (pin_numbers hide) (pin_names hide) (in_bom yes) (on_board yes)
      (property "Reference" "R" (at 20.32 -5.08 0)
        (effects (font (size 1.27 1.27) (thickness 0.15)) (justify left bottom))
      )
      (property "Value" "R_4k7_0402" (at 20.32 -12.7 0)
        (effects (font (size 1.27 1.27) (thickness 0.15)) (justify left bottom) hide)
      )
      (property "Footprint" "sdi-mipi-bridge-footprints:R_0402_1005Metric" (at 20.32 -15.24 0)
        (effects (font (size 1.27 1.27) (thickness 0.15)) (justify left bottom) hide)
      )
      (property "Datasheet" "https://www.bourns.com/docs/product-datasheets/cr.pdf" (at 20.32 -17.78 0)
        (effects (font (size 1.27 1.27) (thickness 0.15)) (justify left bottom) hide)
      )
      (property "MPN" "CR0402-FX-4701GLF" (at 20.32 -20.32 0)
        (effects (font (size 1.27 1.27) (thickness 0.15)) (justify left bottom) hide)
      )
      (property "Manufacturer" "Bourns" (at 20.32 -22.86 0)
        (effects (font (size 1.27 1.27) (thickness 0.15)) (justify left bottom) hide)
      )
      (property "License" "Apache-2.0" (at 20.32 -25.4 0)
        (effects (font (size 1.27 1.27) (thickness 0.15)) (justify left bottom) hide)
      )
      (property "Author" "Antmicro" (at 20.32 -27.94 0)
        (effects (font (size 1.27 1.27) (thickness 0.15)) (justify left bottom) hide)
      )
      (property "Val" "4k7" (at 20.32 -7.62 0)
        (effects (font (size 1.27 1.27) (thickness 0.15)) (justify left bottom))
      )
      (property "Tolerance" "1%" (at 20.32 -10.16 0)
        (effects (font (size 1.27 1.27)) (justify left bottom) hide)
      )
      (property "ki_description" "4k7 resistor in 0402 package with 1% tolerance" (at 0 0 0)
        (effects (font (size 1.27 1.27)) hide)
      )
      (symbol "R_4k7_0402_0_1"
        (rectangle (start 0.635 0.889) (end 4.445 -0.889)
          (stroke (width 0.254) (type default))
          (fill (type none))
        )
      )
      (symbol "R_4k7_0402_1_1"
        (pin passive line (at 0 0 0) (length 0.635)
          (name "~" (effects (font (size 1.27 1.27))))
          (number "1" (effects (font (size 1.27 1.27))))
        )
        (pin passive line (at 5.08 0 180) (length 0.635)
          (name "~" (effects (font (size 1.27 1.27))))
          (number "2" (effects (font (size 1.27 1.27))))
        )
      )
    )
	(symbol "sdi-mipi-bridge:R_750R_0402" (pin_numbers hide) (pin_names hide) (in_bom yes) (on_board yes)
      (property "Reference" "R" (at 20.32 -5.08 0)
        (effects (font (size 1.27 1.27) (thickness 0.15)) (justify left bottom))
      )
      (property "Value" "R_750R_0402" (at 20.32 -12.7 0)
        (effects (font (size 1.27 1.27) (thickness 0.15)) (justify left bottom) hide)
      )
      (property "Footprint" "sdi-mipi-bridge-footprints:R_0402_1005Metric" (at 20.32 -15.24 0)
        (effects (font (size 1.27 1.27) (thickness 0.15)) (justify left bottom) hide)
      )
      (property "Datasheet" "https://www.bourns.com/docs/product-datasheets/cr.pdf" (at 20.32 -17.78 0)
        (effects (font (size 1.27 1.27) (thickness 0.15)) (justify left bottom) hide)
      )
      (property "MPN" "CR0402-FX-7500GLF" (at 20.32 -20.32 0)
        (effects (font (size 1.27 1.27) (thickness 0.15)) (justify left bottom) hide)
      )
      (property "Manufacturer" "Bourns" (at 20.32 -22.86 0)
        (effects (font (size 1.27 1.27) (thickness 0.15)) (justify left bottom) hide)
      )
      (property "License" "Apache-2.0" (at 20.32 -25.4 0)
        (effects (font (size 1.27 1.27) (thickness 0.15)) (justify left bottom) hide)
      )
      (property "Author" "Antmicro" (at 20.32 -27.94 0)
        (effects (font (size 1.27 1.27) (thickness 0.15)) (justify left bottom) hide)
      )
      (property "Val" "750R" (at 20.32 -7.62 0)
        (effects (font (size 1.27 1.27) (thickness 0.15)) (justify left bottom))
      )
      (property "Tolerance" "1%" (at 20.32 -10.16 0)
        (effects (font (size 1.27 1.27)) (justify left bottom) hide)
      )
      (property "ki_description" "750R resistor in 0402 package with 1% tolerance" (at 0 0 0)
        (effects (font (size 1.27 1.27)) hide)
      )
      (symbol "R_750R_0402_0_1"
        (rectangle (start 0.635 0.889) (end 4.445 -0.889)
          (stroke (width 0.254) (type default))
          (fill (type none))
        )
      )
      (symbol "R_750R_0402_1_1"
        (pin passive line (at 0 0 0) (length 0.635)
          (name "~" (effects (font (size 1.27 1.27))))
          (number "1" (effects (font (size 1.27 1.27))))
        )
        (pin passive line (at 5.08 0 180) (length 0.635)
          (name "~" (effects (font (size 1.27 1.27))))
          (number "2" (effects (font (size 1.27 1.27))))
        )
      )
    )
	(symbol "sdi-mipi-bridge:R_75R_0603" (pin_numbers hide) (pin_names hide) (in_bom yes) (on_board yes)
      (property "Reference" "R" (at 20.32 -5.08 0)
        (effects (font (size 1.27 1.27) (thickness 0.15)) (justify left bottom))
      )
      (property "Value" "R_75R_0603" (at 20.32 -12.7 0)
        (effects (font (size 1.27 1.27) (thickness 0.15)) (justify left bottom) hide)
      )
      (property "Footprint" "sdi-mipi-bridge-footprints:R_0603_1608Metric" (at 20.32 -15.24 0)
        (effects (font (size 1.27 1.27) (thickness 0.15)) (justify left bottom) hide)
      )
      (property "Datasheet" "https://www.bourns.com/docs/product-datasheets/cr.pdf" (at 20.32 -17.78 0)
        (effects (font (size 1.27 1.27) (thickness 0.15)) (justify left bottom) hide)
      )
      (property "MPN" "CR0603-FX-75R0ELF" (at 20.32 -20.32 0)
        (effects (font (size 1.27 1.27) (thickness 0.15)) (justify left bottom) hide)
      )
      (property "Manufacturer" "Bourns" (at 20.32 -22.86 0)
        (effects (font (size 1.27 1.27) (thickness 0.15)) (justify left bottom) hide)
      )
      (property "License" "Apache-2.0" (at 20.32 -25.4 0)
        (effects (font (size 1.27 1.27) (thickness 0.15)) (justify left bottom) hide)
      )
      (property "Author" "Antmicro" (at 20.32 -27.94 0)
        (effects (font (size 1.27 1.27) (thickness 0.15)) (justify left bottom) hide)
      )
      (property "Val" "75R" (at 20.32 -7.62 0)
        (effects (font (size 1.27 1.27) (thickness 0.15)) (justify left bottom))
      )
      (property "Tolerance" "1%" (at 20.32 -10.16 0)
        (effects (font (size 1.27 1.27)) (justify left bottom) hide)
      )
      (property "ki_description" "75R resistor in 0603 package with 1% tolerance" (at 0 0 0)
        (effects (font (size 1.27 1.27)) hide)
      )
      (symbol "R_75R_0603_0_1"
        (rectangle (start 0.635 0.889) (end 4.445 -0.889)
          (stroke (width 0.254) (type default))
          (fill (type none))
        )
      )
      (symbol "R_75R_0603_1_1"
        (pin passive line (at 0 0 0) (length 0.635)
          (name "~" (effects (font (size 1.27 1.27))))
          (number "1" (effects (font (size 1.27 1.27))))
        )
        (pin passive line (at 5.08 0 180) (length 0.635)
          (name "~" (effects (font (size 1.27 1.27))))
          (number "2" (effects (font (size 1.27 1.27))))
        )
      )
    )
	(symbol "sdi-mipi-bridge:SC18IS602BIPW" (in_bom yes) (on_board yes)
      (property "Reference" "U" (at 53.34 -2.54 0)
        (effects (font (size 1.27 1.27) (thickness 0.15)) (justify left bottom))
      )
      (property "Value" "SC18IS602BIPW" (at 53.34 -5.08 0)
        (effects (font (size 1.27 1.27) (thickness 0.15)) (justify left bottom))
      )
      (property "Footprint" "sdi-mipi-bridge-footprints:TSSOP-16_4.4x5mm_P0.65mm" (at 53.34 -7.62 0)
        (effects (font (size 1.27 1.27) (thickness 0.15)) (justify left bottom) hide)
      )
      (property "Datasheet" "https://www.nxp.com/docs/en/data-sheet/SC18IS602B.pdf" (at 53.34 -10.16 0)
        (effects (font (size 1.27 1.27) (thickness 0.15)) (justify left bottom) hide)
      )
      (property "Manufacturer" "NXP" (at 53.34 -12.7 0)
        (effects (font (size 1.27 1.27) (thickness 0.15)) (justify left bottom) hide)
      )
      (property "MPN" "SC18IS602BIPW" (at 53.34 -15.24 0)
        (effects (font (size 1.27 1.27) (thickness 0.15)) (justify left bottom) hide)
      )
      (property "Author" "Antmicro" (at 53.34 -17.78 0)
        (effects (font (size 1.27 1.27) (thickness 0.15)) (justify left bottom) hide)
      )
      (property "License" "Apache-2.0" (at 53.34 -20.32 0)
        (effects (font (size 1.27 1.27) (thickness 0.15)) (justify left bottom) hide)
      )
      (symbol "SC18IS602BIPW_1_1"
        (rectangle (start 2.54 2.54) (end 25.4 -27.94)
          (stroke (width 0.254) (type default))
          (fill (type background))
        )
        (pin bidirectional line (at 27.94 -15.24 180) (length 2.54)
          (name "GPIO0/~{SS0}" (effects (font (size 1.27 1.27))))
          (number "1" (effects (font (size 1.27 1.27))))
        )
        (pin bidirectional line (at 27.94 -20.32 180) (length 2.54)
          (name "GPIO2/~{SS2}" (effects (font (size 1.27 1.27))))
          (number "10" (effects (font (size 1.27 1.27))))
        )
        (pin output line (at 27.94 -10.16 180) (length 2.54)
          (name "SCLK" (effects (font (size 1.27 1.27))))
          (number "11" (effects (font (size 1.27 1.27))))
        )
        (pin power_in line (at 0 0 0) (length 2.54)
          (name "V_{DD}" (effects (font (size 1.27 1.27))))
          (number "12" (effects (font (size 1.27 1.27))))
        )
        (pin bidirectional line (at 27.94 -22.86 180) (length 2.54)
          (name "GPIO3/~{SS3}" (effects (font (size 1.27 1.27))))
          (number "13" (effects (font (size 1.27 1.27))))
        )
        (pin input line (at 0 -17.78 0) (length 2.54)
          (name "A0" (effects (font (size 1.27 1.27))))
          (number "14" (effects (font (size 1.27 1.27))))
        )
        (pin input line (at 0 -20.32 0) (length 2.54)
          (name "A1" (effects (font (size 1.27 1.27))))
          (number "15" (effects (font (size 1.27 1.27))))
        )
        (pin input line (at 0 -22.86 0) (length 2.54)
          (name "A2" (effects (font (size 1.27 1.27))))
          (number "16" (effects (font (size 1.27 1.27))))
        )
        (pin bidirectional line (at 27.94 -17.78 180) (length 2.54)
          (name "GPIO1/~{SS1}" (effects (font (size 1.27 1.27))))
          (number "2" (effects (font (size 1.27 1.27))))
        )
        (pin input line (at 0 -2.54 0) (length 2.54)
          (name "~{RESET}" (effects (font (size 1.27 1.27))))
          (number "3" (effects (font (size 1.27 1.27))))
        )
        (pin power_in line (at 0 -25.4 0) (length 2.54)
          (name "V_{SS}" (effects (font (size 1.27 1.27))))
          (number "4" (effects (font (size 1.27 1.27))))
        )
        (pin input line (at 27.94 -5.08 180) (length 2.54)
          (name "MISO" (effects (font (size 1.27 1.27))))
          (number "5" (effects (font (size 1.27 1.27))))
        )
        (pin output line (at 27.94 -7.62 180) (length 2.54)
          (name "MOSI" (effects (font (size 1.27 1.27))))
          (number "6" (effects (font (size 1.27 1.27))))
        )
        (pin bidirectional line (at 0 -10.16 0) (length 2.54)
          (name "SDA" (effects (font (size 1.27 1.27))))
          (number "7" (effects (font (size 1.27 1.27))))
        )
        (pin input line (at 0 -12.7 0) (length 2.54)
          (name "SCL" (effects (font (size 1.27 1.27))))
          (number "8" (effects (font (size 1.27 1.27))))
        )
        (pin output line (at 0 -7.62 0) (length 2.54)
          (name "~{INT}" (effects (font (size 1.27 1.27))))
          (number "9" (effects (font (size 1.27 1.27))))
        )
      )
    )
	(symbol "sdi-mipi-bridge:SW_SPST_KMR211NGLFS" (in_bom yes) (on_board yes)
      (property "Reference" "SW" (at 25.4 -2.54 0)
        (effects (font (size 1.27 1.27) (thickness 0.15)) (justify left bottom))
      )
      (property "Value" "SW_SPST_KMR211NGLFS" (at 25.4 -5.08 0)
        (effects (font (size 1.27 1.27) (thickness 0.15)) (justify left bottom))
      )
      (property "Footprint" "sdi-mipi-bridge-footprints:SW_SPST_4.2x2.8" (at 25.4 -7.62 0)
        (effects (font (size 1.27 1.27) (thickness 0.15)) (justify left bottom) hide)
      )
      (property "Datasheet" "http://www.farnell.com/datasheets/2631211.pdf" (at 25.4 -10.16 0)
        (effects (font (size 1.27 1.27) (thickness 0.15)) (justify left bottom) hide)
      )
      (property "MPN" "KMR211NGLFS" (at 25.4 -12.7 0)
        (effects (font (size 1.27 1.27) (thickness 0.15)) (justify left bottom) hide)
      )
      (property "Manufacturer" "C&K" (at 25.4 -15.24 0)
        (effects (font (size 1.27 1.27) (thickness 0.15)) (justify left bottom) hide)
      )
      (property "Author" "Antmicro" (at 25.4 -17.78 0)
        (effects (font (size 1.27 1.27) (thickness 0.15)) (justify left bottom) hide)
      )
      (property "License" "Apache-2.0" (at 25.4 -20.32 0)
        (effects (font (size 1.27 1.27) (thickness 0.15)) (justify left bottom) hide)
      )
      (symbol "SW_SPST_KMR211NGLFS_1_1"
        (polyline
          (pts
            (xy 2.54 -2.54)
            (xy 3.302 -2.54)
          )
          (stroke (width 0.254) (type default))
          (fill (type background))
        )
        (polyline
          (pts
            (xy 2.54 0)
            (xy 3.302 0)
          )
          (stroke (width 0.254) (type default))
          (fill (type background))
        )
        (polyline
          (pts
            (xy 3.302 1.27)
            (xy 6.858 1.27)
          )
          (stroke (width 0.254) (type default))
          (fill (type background))
        )
        (polyline
          (pts
            (xy 3.556 -0.3048)
            (xy 3.556 -2.1844)
          )
          (stroke (width 0.254) (type default))
          (fill (type background))
        )
        (polyline
          (pts
            (xy 4.064 2.794)
            (xy 6.096 2.794)
          )
          (stroke (width 0.254) (type default))
          (fill (type background))
        )
        (polyline
          (pts
            (xy 5.08 1.27)
            (xy 5.08 2.794)
          )
          (stroke (width 0.254) (type default))
          (fill (type background))
        )
        (polyline
          (pts
            (xy 6.604 -0.254)
            (xy 6.604 -2.1844)
          )
          (stroke (width 0.254) (type default))
          (fill (type background))
        )
        (polyline
          (pts
            (xy 7.62 -2.54)
            (xy 6.858 -2.54)
          )
          (stroke (width 0.254) (type default))
          (fill (type background))
        )
        (polyline
          (pts
            (xy 7.62 0)
            (xy 6.858 0)
          )
          (stroke (width 0.254) (type default))
          (fill (type background))
        )
        (circle (center 3.556 -2.54) (radius 0.254)
          (stroke (width 0.254) (type default))
          (fill (type outline))
        )
        (circle (center 3.556 0) (radius 0.254)
          (stroke (width 0.254) (type default))
          (fill (type outline))
        )
        (circle (center 6.604 -2.54) (radius 0.254)
          (stroke (width 0.254) (type default))
          (fill (type outline))
        )
        (circle (center 6.604 0) (radius 0.254)
          (stroke (width 0.254) (type default))
          (fill (type outline))
        )
        (pin passive line (at 0 0 0) (length 2.54)
          (name "~" (effects (font (size 1.27 1.27))))
          (number "1" (effects (font (size 1.27 1.27))))
        )
        (pin passive line (at 10.16 0 180) (length 2.54)
          (name "~" (effects (font (size 1.27 1.27))))
          (number "2" (effects (font (size 1.27 1.27))))
        )
        (pin passive line (at 0 -2.54 0) (length 2.54)
          (name "~" (effects (font (size 1.27 1.27))))
          (number "3" (effects (font (size 1.27 1.27))))
        )
        (pin passive line (at 10.16 -2.54 180) (length 2.54)
          (name "~" (effects (font (size 1.27 1.27))))
          (number "4" (effects (font (size 1.27 1.27))))
        )
      )
    )
	(symbol "sdi-mipi-bridge:TP_0.75mm_SMD" (pin_numbers hide) (pin_names hide) (in_bom yes) (on_board yes)
      (property "Reference" "TP" (at 17.78 -5.08 0)
        (effects (font (size 1.27 1.27) (thickness 0.15)) (justify left bottom))
      )
      (property "Value" "TP_0.75mm_SMD" (at 17.78 -7.62 0)
        (effects (font (size 1.27 1.27) (thickness 0.15)) (justify left bottom) hide)
      )
      (property "Footprint" "sdi-mipi-bridge-footprints:TP_SMD_0.75mm" (at 17.78 -10.16 0)
        (effects (font (size 1.27 1.27) (thickness 0.15)) (justify left bottom) hide)
      )
      (property "Datasheet" "" (at 17.78 -12.7 0)
        (effects (font (size 1.27 1.27) (thickness 0.15)) (justify left bottom) hide)
      )
      (property "MPN" "" (at 17.78 -15.24 0)
        (effects (font (size 1.27 1.27) (thickness 0.15)) (justify left bottom) hide)
      )
      (property "Manufacturer" "" (at 17.78 -17.78 0)
        (effects (font (size 1.27 1.27) (thickness 0.15)) (justify left bottom) hide)
      )
      (property "Author" "Antmicro" (at 17.78 -20.32 0)
        (effects (font (size 1.27 1.27) (thickness 0.15)) (justify left bottom) hide)
      )
      (property "License" "Apache-2.0" (at 17.78 -22.86 0)
        (effects (font (size 1.27 1.27) (thickness 0.15)) (justify left bottom) hide)
      )
      (property "ki_description" "Test Point 0.75mm" (at 0 0 0)
        (effects (font (size 1.27 1.27)) hide)
      )
      (symbol "TP_0.75mm_SMD_1_1"
        (circle (center 3.175 0) (radius 0.635)
          (stroke (width 0.254) (type default))
          (fill (type none))
        )
        (pin passive line (at 0 0 0) (length 2.54)
          (name "1" (effects (font (size 1.27 1.27))))
          (number "1" (effects (font (size 1.27 1.27))))
        )
      )
    )
	(symbol "sdi-mipi-bridge:TP_1mm_SMD" (pin_numbers hide) (pin_names hide) (in_bom yes) (on_board yes)
      (property "Reference" "TP" (at 15.24 -5.08 0)
        (effects (font (size 1.27 1.27) (thickness 0.15)) (justify left bottom))
      )
      (property "Value" "TP_1mm_SMD" (at 15.24 -7.62 0)
        (effects (font (size 1.27 1.27) (thickness 0.15)) (justify left bottom) hide)
      )
      (property "Footprint" "sdi-mipi-bridge-footprints:Testpoint_smd_1mm" (at 15.24 -10.16 0)
        (effects (font (size 1.27 1.27) (thickness 0.15)) (justify left bottom) hide)
      )
      (property "Datasheet" "" (at 15.24 -12.7 0)
        (effects (font (size 1.27 1.27) (thickness 0.15)) (justify left bottom) hide)
      )
      (property "MPN" "" (at 0 0 0)
        (effects (font (size 1.27 1.27)) hide)
      )
      (property "Manufacturer" "" (at 0 0 0)
        (effects (font (size 1.27 1.27)) hide)
      )
      (property "Author" "Antmicro" (at 15.24 -15.24 0)
        (effects (font (size 1.27 1.27) (thickness 0.15)) (justify left bottom) hide)
      )
      (property "License" "Apache-2.0" (at 15.24 -17.78 0)
        (effects (font (size 1.27 1.27) (thickness 0.15)) (justify left bottom) hide)
      )
      (property "ki_description" "Test Point 1mm" (at 0 0 0)
        (effects (font (size 1.27 1.27)) hide)
      )
      (symbol "TP_1mm_SMD_1_1"
        (circle (center 3.175 0) (radius 0.635)
          (stroke (width 0.254) (type default))
          (fill (type none))
        )
        (pin passive line (at 0 0 0) (length 2.54)
          (name "1" (effects (font (size 1.27 1.27))))
          (number "1" (effects (font (size 1.27 1.27))))
        )
      )
    )
	(symbol "sdi-mipi-bridge:VDD" (power) (pin_names (offset 0)) (in_bom yes) (on_board yes)
      (property "Reference" "#PWR" (at 0 -3.81 0)
        (effects (font (size 1.27 1.27)) hide)
      )
      (property "Value" "VDD" (at 0 3.81 0)
        (effects (font (size 1.27 1.27)))
      )
      (property "Footprint" "" (at 0 0 0)
        (effects (font (size 1.27 1.27)) hide)
      )
      (property "Datasheet" "" (at 0 0 0)
        (effects (font (size 1.27 1.27)) hide)
      )
      (symbol "VDD_0_1"
        (polyline
          (pts
            (xy -0.762 1.27)
            (xy 0 2.54)
          )
          (stroke (width 0) (type default))
          (fill (type none))
        )
        (polyline
          (pts
            (xy 0 0)
            (xy 0 2.54)
          )
          (stroke (width 0) (type default))
          (fill (type none))
        )
        (polyline
          (pts
            (xy 0 2.54)
            (xy 0.762 1.27)
          )
          (stroke (width 0) (type default))
          (fill (type none))
        )
      )
      (symbol "VDD_1_1"
        (pin power_in line (at 0 0 90) (length 0) hide
          (name "VDD" (effects (font (size 1.27 1.27))))
          (number "1" (effects (font (size 1.27 1.27))))
        )
      )
    )
	(symbol "sdi-mipi-bridge:VPP" (power) (pin_names (offset 0)) (in_bom yes) (on_board yes)
      (property "Reference" "#PWR" (at 0 -3.81 0)
        (effects (font (size 1.27 1.27)) hide)
      )
      (property "Value" "VPP" (at 0 3.81 0)
        (effects (font (size 1.27 1.27)))
      )
      (property "Footprint" "" (at 0 0 0)
        (effects (font (size 1.27 1.27)) hide)
      )
      (property "Datasheet" "" (at 0 0 0)
        (effects (font (size 1.27 1.27)) hide)
      )
      (symbol "VPP_0_1"
        (polyline
          (pts
            (xy -0.762 1.27)
            (xy 0 2.54)
          )
          (stroke (width 0) (type default))
          (fill (type none))
        )
        (polyline
          (pts
            (xy 0 0)
            (xy 0 2.54)
          )
          (stroke (width 0) (type default))
          (fill (type none))
        )
        (polyline
          (pts
            (xy 0 2.54)
            (xy 0.762 1.27)
          )
          (stroke (width 0) (type default))
          (fill (type none))
        )
      )
      (symbol "VPP_1_1"
        (pin power_in line (at 0 0 90) (length 0) hide
          (name "VPP" (effects (font (size 1.27 1.27))))
          (number "1" (effects (font (size 1.27 1.27))))
        )
      )
    )
	(symbol "sdi-mipi-bridge:antmicro_logo" (in_bom yes) (on_board yes)
      (property "Reference" "N" (at 15.24 -5.08 0)
        (effects (font (size 1.27 1.27) (thickness 0.15)) (justify left bottom))
      )
      (property "Value" "antmicro_logo" (at 15.24 -7.62 0)
        (effects (font (size 1.27 1.27) (thickness 0.15)) (justify left bottom))
      )
      (property "Footprint" "sdi-mipi-bridge-footprints:antmicro-logo" (at 15.24 -10.16 0)
        (effects (font (size 1.27 1.27) (thickness 0.15)) (justify left bottom) hide)
      )
      (property "Datasheet" "" (at 15.24 -12.7 0)
        (effects (font (size 1.27 1.27) (thickness 0.15)) (justify left bottom) hide)
      )
      (property "MPN" "" (at 0 0 0)
        (effects (font (size 1.27 1.27)) hide)
      )
      (property "Manufacturer" "" (at 15.24 -20.32 0)
        (effects (font (size 1.27 1.27) (thickness 0.15)) (justify left bottom) hide)
      )
      (property "Author" "Antmicro" (at 15.24 -15.24 0)
        (effects (font (size 1.27 1.27) (thickness 0.15)) (justify left bottom) hide)
      )
      (property "License" "Apache-2.0" (at 15.24 -17.78 0)
        (effects (font (size 1.27 1.27) (thickness 0.15)) (justify left bottom) hide)
      )
      (symbol "antmicro_logo_1_1"
        (text "Logo" (at 0 0 0)
          (effects (font (size 1.27 1.27) (thickness 0.15)) (justify left bottom))
        )
      )
    )
	(symbol "sdi-mipi-bridge:oshw_logo" (in_bom yes) (on_board yes)
      (property "Reference" "N" (at 15.24 -5.08 0)
        (effects (font (size 1.27 1.27) (thickness 0.15)) (justify left bottom))
      )
      (property "Value" "oshw_logo" (at 15.24 -7.62 0)
        (effects (font (size 1.27 1.27) (thickness 0.15)) (justify left bottom))
      )
      (property "Footprint" "sdi-mipi-bridge-footprints:oshw-logo" (at 15.24 -10.16 0)
        (effects (font (size 1.27 1.27) (thickness 0.15)) (justify left bottom) hide)
      )
      (property "Datasheet" "" (at 15.24 -12.7 0)
        (effects (font (size 1.27 1.27) (thickness 0.15)) (justify left bottom) hide)
      )
      (property "Author" "Antmicro" (at 15.24 -15.24 0)
        (effects (font (size 1.27 1.27) (thickness 0.15)) (justify left bottom) hide)
      )
      (property "License" "Apache-2.0" (at 15.24 -17.78 0)
        (effects (font (size 1.27 1.27) (thickness 0.15)) (justify left bottom) hide)
      )
      (property "MPN" "" (at 0 0 0)
        (effects (font (size 1.27 1.27)) hide)
      )
      (property "Manufacturer" "" (at 15.24 -20.32 0)
        (effects (font (size 1.27 1.27) (thickness 0.15)) (justify left bottom) hide)
      )
      (symbol "oshw_logo_1_1"
        (text "Logo" (at 0 0 0)
          (effects (font (size 1.27 1.27) (thickness 0.15)) (justify left bottom))
        )
      )
    )
)
